FILE_TYPE = MACRO_DRAWING;
SET COLOR_WIRE YELLOW;
SET COLOR_PROP ORANGE;
SET COLOR_DOT WHITE;
SET COLOR_ARC YELLOW;
SET COLOR_BODY GREEN;
SET COLOR_NOTE PURPLE;
SET PROP_DISPLAY VALUE;
SET PAGE_NUMBER P178;
FORCEADD UNIVERSAL_GND..1
(950 1650);
FORCEPROP 3 LASTPIN (950 1700) SIG_NAME GND\g
J 0
(960 1710);
DISPLAY 0.659574 (960 1710);
PAINT MONO (960 1710);
DISPLAY INVISIBLE (960 1710);
FORCEPROP 2 LAST CDS_LIB pure_quanta_power
J 0
(950 1650);
DISPLAY INVISIBLE (950 1650);
FORCEPROP 1 LAST HDL_POWER GND
J 1
(975 1575);
DISPLAY 0.872340 (975 1575);
PAINT GREEN (975 1575);
DISPLAY INVISIBLE (975 1575);
FORCEPROP 1 LAST PATH I1
J 0
(1025 1650);
DISPLAY 0.872340 (1025 1650);
PAINT AQUA (1025 1650);
DISPLAY INVISIBLE (1025 1650);
FORCEADD Q_CAP..1
(975 4500);
FORCEPROP 1 LAST LOCATION PC132_5
J 0
(1025 4600);
DISPLAY 0.489362 (1025 4600);
PAINT SKYBLUE (1025 4600);
FORCEPROP 0 LAST $SEC 1
J 0
(1025 4625);
DISPLAY 0.680851 (1025 4625);
PAINT MONO (1025 4625);
DISPLAY INVISIBLE (1025 4625);
FORCEPROP 0 LAST CDS_SEC 1
J 0
(1225 4550);
DISPLAY 1.021277 (1225 4550);
DISPLAY INVISIBLE (1225 4550);
FORCEPROP 1 LASTPIN (975 4600) $PN 1
J 0
(985 4580);
DISPLAY 0.489362 (985 4580);
PAINT MONO (985 4580);
FORCEPROP 1 LASTPIN (975 4400) $PN 2
J 0
(985 4380);
DISPLAY 0.489362 (985 4380);
PAINT MONO (985 4380);
FORCEPROP 1 LAST PACK_TYPE 0402
J 0
(1025 4300);
DISPLAY 0.489362 (1025 4300);
PAINT SKYBLUE (1025 4300);
FORCEPROP 1 LAST VOLTAGE 25V
J 0
(1025 4500);
DISPLAY 0.489362 (1025 4500);
PAINT SKYBLUE (1025 4500);
FORCEPROP 1 LAST VALUE 0.1UF
J 0
(1025 4550);
DISPLAY 0.489362 (1025 4550);
PAINT SKYBLUE (1025 4550);
FORCEPROP 1 LAST TOLERANCE 10%
J 0
(1025 4450);
DISPLAY 0.489362 (1025 4450);
PAINT SKYBLUE (1025 4450);
FORCEPROP 1 LAST MATERIAL X7R
J 0
(1025 4400);
DISPLAY 0.489362 (1025 4400);
PAINT SKYBLUE (1025 4400);
FORCEPROP 2 LAST CDS_LIB pure_quanta
J 0
(975 4500);
DISPLAY INVISIBLE (975 4500);
FORCEPROP 1 LAST PATH I10
J 0
(1025 4650);
DISPLAY 0.978723 (1025 4650);
PAINT WHITE (1025 4650);
DISPLAY INVISIBLE (1025 4650);
FORCEPROP 1 LAST PART_NUMBER CH4104K1B00
J 0
(1025 4350);
DISPLAY 0.489362 (1025 4350);
PAINT SKYBLUE (1025 4350);
DISPLAY INVISIBLE (1025 4350);
FORCEADD Q_CAP..1
(1900 2650);
FORCEPROP 1 LAST LOCATION PC112
J 0
(1950 2750);
DISPLAY 0.489362 (1950 2750);
PAINT SKYBLUE (1950 2750);
FORCEPROP 0 LAST $SEC 1
J 0
(1950 2800);
DISPLAY 0.680851 (1950 2800);
PAINT MONO (1950 2800);
DISPLAY INVISIBLE (1950 2800);
FORCEPROP 0 LAST CDS_SEC 1
J 0
(1950 2800);
DISPLAY 1.021277 (1950 2800);
DISPLAY INVISIBLE (1950 2800);
FORCEPROP 1 LASTPIN (1900 2750) $PN 1
J 0
(1910 2730);
DISPLAY 0.489362 (1910 2730);
PAINT MONO (1910 2730);
FORCEPROP 1 LASTPIN (1900 2550) $PN 2
J 0
(1910 2530);
DISPLAY 0.489362 (1910 2530);
PAINT MONO (1910 2530);
FORCEPROP 1 LAST PACK_TYPE C0402
J 0
(1950 2450);
DISPLAY 0.489362 (1950 2450);
PAINT SKYBLUE (1950 2450);
FORCEPROP 1 LAST VOLTAGE 10V
J 0
(1950 2650);
DISPLAY 0.489362 (1950 2650);
PAINT SKYBLUE (1950 2650);
FORCEPROP 1 LAST VALUE 2.2UF
J 0
(1950 2700);
DISPLAY 0.489362 (1950 2700);
PAINT SKYBLUE (1950 2700);
FORCEPROP 1 LAST TOLERANCE 10%
J 0
(1950 2600);
DISPLAY 0.489362 (1950 2600);
PAINT SKYBLUE (1950 2600);
FORCEPROP 1 LAST MATERIAL X6S
J 0
(1950 2550);
DISPLAY 0.489362 (1950 2550);
PAINT SKYBLUE (1950 2550);
FORCEPROP 2 LAST CDS_LIB pure_quanta
J 0
(1900 2650);
DISPLAY INVISIBLE (1900 2650);
FORCEPROP 1 LAST PATH I11
J 0
(1950 2800);
DISPLAY 0.978723 (1950 2800);
PAINT WHITE (1950 2800);
DISPLAY INVISIBLE (1950 2800);
FORCEPROP 1 LAST PART_NUMBER CH5222KEB01
J 0
(1950 2500);
DISPLAY 0.489362 (1950 2500);
PAINT SKYBLUE (1950 2500);
DISPLAY INVISIBLE (1950 2500);
FORCEADD UNIVERSAL_GND..1
(1900 2450);
FORCEPROP 3 LASTPIN (1900 2500) SIG_NAME GND\g
J 0
(1910 2510);
DISPLAY 0.659574 (1910 2510);
PAINT MONO (1910 2510);
DISPLAY INVISIBLE (1910 2510);
FORCEPROP 2 LAST CDS_LIB pure_quanta_power
J 0
(1900 2450);
DISPLAY INVISIBLE (1900 2450);
FORCEPROP 1 LAST HDL_POWER GND
J 1
(1925 2375);
DISPLAY 0.872340 (1925 2375);
PAINT GREEN (1925 2375);
DISPLAY INVISIBLE (1925 2375);
FORCEPROP 1 LAST PATH I12
J 0
(1975 2450);
DISPLAY 0.872340 (1975 2450);
PAINT AQUA (1975 2450);
DISPLAY INVISIBLE (1975 2450);
FORCEADD Q_RES..2
(1900 3200);
FORCEPROP 1 LAST LOCATION PR416
J 0
(1945 3325);
DISPLAY 0.489362 (1945 3325);
PAINT SKYBLUE (1945 3325);
FORCEPROP 0 LAST $SEC 1
J 0
(1950 3375);
DISPLAY 0.680851 (1950 3375);
PAINT MONO (1950 3375);
DISPLAY INVISIBLE (1950 3375);
FORCEPROP 0 LAST CDS_SEC 1
J 0
(1950 3375);
DISPLAY 1.021277 (1950 3375);
DISPLAY INVISIBLE (1950 3375);
FORCEPROP 1 LASTPIN (1900 3300) $PN 1
J 0
(1905 3262);
DISPLAY 0.489362 (1905 3262);
PAINT MONO (1905 3262);
FORCEPROP 1 LASTPIN (1900 3100) $PN 2
J 0
(1905 3110);
DISPLAY 0.489362 (1905 3110);
PAINT MONO (1905 3110);
FORCEPROP 1 LAST PACK_TYPE 0402LF
J 0
(1950 3025);
DISPLAY 0.489362 (1950 3025);
PAINT SKYBLUE (1950 3025);
FORCEPROP 1 LAST WATTAGE 1/16W
J 0
(1950 3175);
DISPLAY 0.489362 (1950 3175);
PAINT SKYBLUE (1950 3175);
FORCEPROP 1 LAST MATERIAL CHIP
J 0
(1950 3125);
DISPLAY 0.489362 (1950 3125);
PAINT SKYBLUE (1950 3125);
FORCEPROP 1 LAST TOLERANCE 1%
J 0
(1950 3225);
DISPLAY 0.489362 (1950 3225);
PAINT SKYBLUE (1950 3225);
FORCEPROP 1 LAST VALUE 2.2
J 0
(1950 3275);
DISPLAY 0.489362 (1950 3275);
PAINT SKYBLUE (1950 3275);
FORCEPROP 2 LAST CDS_LIB pure_quanta
J 0
(1900 3200);
DISPLAY INVISIBLE (1900 3200);
FORCEPROP 1 LAST PATH I13
J 0
(1950 3375);
DISPLAY 0.978723 (1950 3375);
PAINT WHITE (1950 3375);
DISPLAY INVISIBLE (1950 3375);
FORCEPROP 1 LAST PART_NUMBER CS-2202FB01
J 0
(1950 3075);
DISPLAY 0.489362 (1950 3075);
PAINT SKYBLUE (1950 3075);
DISPLAY INVISIBLE (1950 3075);
FORCEADD UNIVERSAL_GND..1
(1475 4150);
FORCEPROP 3 LASTPIN (1475 4200) SIG_NAME GND\g
J 0
(1485 4210);
DISPLAY 0.659574 (1485 4210);
PAINT MONO (1485 4210);
DISPLAY INVISIBLE (1485 4210);
FORCEPROP 2 LAST CDS_LIB pure_quanta_power
J 0
(1475 4150);
PAINT MONO (1475 4150);
DISPLAY INVISIBLE (1475 4150);
FORCEPROP 1 LAST HDL_POWER GND
J 1
(1500 4075);
DISPLAY 0.872340 (1500 4075);
PAINT GREEN (1500 4075);
DISPLAY INVISIBLE (1500 4075);
FORCEPROP 1 LAST PATH I14
J 0
(1550 4150);
DISPLAY 0.872340 (1550 4150);
PAINT AQUA (1550 4150);
DISPLAY INVISIBLE (1550 4150);
FORCEADD Q_RES..2
R 2
(1475 4375);
FORCEPROP 1 LAST LOCATION PR93
J 2
(1430 4500);
DISPLAY 0.489362 (1430 4500);
PAINT SKYBLUE (1430 4500);
FORCEPROP 0 LAST $SEC 1
J 0
(1450 4550);
DISPLAY 0.680851 (1450 4550);
PAINT MONO (1450 4550);
DISPLAY INVISIBLE (1450 4550);
FORCEPROP 0 LAST CDS_SEC 1
J 0
(1450 4550);
DISPLAY 1.021277 (1450 4550);
DISPLAY INVISIBLE (1450 4550);
FORCEPROP 1 LASTPIN (1475 4475) $PN 1
J 2
(1470 4437);
DISPLAY 0.489362 (1470 4437);
PAINT MONO (1470 4437);
FORCEPROP 1 LASTPIN (1475 4275) $PN 2
J 2
(1470 4285);
DISPLAY 0.489362 (1470 4285);
PAINT MONO (1470 4285);
FORCEPROP 1 LAST WATTAGE 1/16W
J 2
(1435 4350);
DISPLAY 0.489362 (1435 4350);
PAINT SKYBLUE (1435 4350);
FORCEPROP 1 LAST MATERIAL EMPTY
J 2
(1435 4300);
DISPLAY 0.489362 (1435 4300);
PAINT RED (1435 4300);
FORCEPROP 1 LAST TOLERANCE 1%
J 2
(1430 4400);
DISPLAY 0.489362 (1430 4400);
PAINT SKYBLUE (1430 4400);
FORCEPROP 1 LAST VALUE 8.87K
J 2
(1430 4450);
DISPLAY 0.489362 (1430 4450);
PAINT SKYBLUE (1430 4450);
FORCEPROP 1 LAST PACK_TYPE 0402LF
J 2
(1435 4200);
DISPLAY 0.489362 (1435 4200);
PAINT SKYBLUE (1435 4200);
FORCEPROP 2 LAST CDS_LIB pure_quanta
J 2
(1475 4375);
DISPLAY INVISIBLE (1475 4375);
FORCEPROP 1 LAST PATH I15
J 2
(1425 4550);
DISPLAY 0.978723 (1425 4550);
PAINT WHITE (1425 4550);
DISPLAY INVISIBLE (1425 4550);
FORCEPROP 1 LAST PART_NUMBER CS28872FB01
J 2
(1435 4250);
DISPLAY 0.489362 (1435 4250);
PAINT SKYBLUE (1435 4250);
DISPLAY INVISIBLE (1435 4250);
FORCEADD VCC_CORE..1
(1900 3625);
FORCEPROP 3 LASTPIN (1900 3575) SIG_NAME PVDDCR_CPU1_P0_PVCC\g
J 0
(1910 3585);
DISPLAY 0.659574 (1910 3585);
PAINT MONO (1910 3585);
DISPLAY INVISIBLE (1910 3585);
FORCEPROP 1 LAST HDL_POWER PVDDCR_CPU1_P0_PVCC
J 1
(1900 3675);
DISPLAY 0.489362 (1900 3675);
PAINT GREEN (1900 3675);
FORCEPROP 2 LAST CDS_LIB pure_quanta_power
J 0
(1900 3625);
DISPLAY INVISIBLE (1900 3625);
FORCEPROP 1 LAST PATH I16
J 0
(1950 3650);
DISPLAY 0.872340 (1950 3650);
PAINT AQUA (1950 3650);
DISPLAY INVISIBLE (1950 3650);
FORCEADD OFFPAGE..5
(1950 4375);
FORCEPROP 2 LAST $XR3 200 
J 0
(1695 4447);
DISPLAY 0.638298 (1695 4447);
PAINT MONO (1695 4447);
FORCEPROP 2 LAST $XR2 203 
J 0
(1695 4411);
DISPLAY 0.638298 (1695 4411);
PAINT MONO (1695 4411);
FORCEPROP 2 LAST $XR1 202 
J 0
(1695 4339);
DISPLAY 0.638298 (1695 4339);
PAINT MONO (1695 4339);
FORCEPROP 2 LAST $XR0 201 
J 0
(1695 4375);
DISPLAY 0.638298 (1695 4375);
PAINT MONO (1695 4375);
FORCEPROP 2 LAST CDS_LIB standard
J 0
(1950 4375);
DISPLAY INVISIBLE (1950 4375);
FORCEPROP 1 LAST OFFPAGE TRUE
J 0
(2275 4250);
DISPLAY 0.872340 (2275 4250);
PAINT GREEN (2275 4250);
DISPLAY INVISIBLE (2275 4250);
FORCEPROP 1 LAST COMMENT_BODY TRUE
J 0
(2050 4300);
DISPLAY 0.872340 (2050 4300);
PAINT GREEN (2050 4300);
DISPLAY INVISIBLE (2050 4300);
FORCEPROP 2 LAST PATH I17
J 0
(1675 4500);
DISPLAY 0.680851 (1675 4500);
DISPLAY INVISIBLE (1675 4500);
FORCEADD OFFPAGE..1
(1950 4275);
FORCEPROP 2 LAST $XR0 200 
J 0
(1698 4275);
DISPLAY 0.638298 (1698 4275);
PAINT MONO (1698 4275);
FORCEPROP 2 LAST CDS_LIB standard
J 0
(1950 4275);
DISPLAY INVISIBLE (1950 4275);
FORCEPROP 1 LAST OFFPAGE TRUE
J 0
(2275 4150);
DISPLAY 0.872340 (2275 4150);
PAINT GREEN (2275 4150);
DISPLAY INVISIBLE (2275 4150);
FORCEPROP 1 LAST COMMENT_BODY TRUE
J 0
(2075 4175);
DISPLAY 0.872340 (2075 4175);
PAINT GREEN (2075 4175);
DISPLAY INVISIBLE (2075 4175);
FORCEPROP 2 LAST PATH I18
J 0
(1700 4325);
DISPLAY 0.680851 (1700 4325);
DISPLAY INVISIBLE (1700 4325);
FORCEADD UNIVERSAL_GND..1
(4025 1500);
FORCEPROP 3 LASTPIN (4025 1550) SIG_NAME GND\g
J 0
(4035 1560);
DISPLAY 0.659574 (4035 1560);
PAINT MONO (4035 1560);
DISPLAY INVISIBLE (4035 1560);
FORCEPROP 2 LAST CDS_LIB pure_quanta_power
J 0
(4025 1500);
PAINT MONO (4025 1500);
DISPLAY INVISIBLE (4025 1500);
FORCEPROP 1 LAST HDL_POWER GND
J 1
(4050 1425);
DISPLAY 0.872340 (4050 1425);
PAINT GREEN (4050 1425);
DISPLAY INVISIBLE (4050 1425);
FORCEPROP 1 LAST PATH I19
J 0
(4100 1500);
DISPLAY 0.872340 (4100 1500);
PAINT AQUA (4100 1500);
DISPLAY INVISIBLE (4100 1500);
FORCEADD Q_CAP..1
(950 1850);
FORCEPROP 1 LAST LOCATION PC111_6
J 0
(1000 1950);
DISPLAY 0.489362 (1000 1950);
PAINT SKYBLUE (1000 1950);
FORCEPROP 0 LAST $SEC 1
J 0
(1000 1975);
DISPLAY 0.680851 (1000 1975);
PAINT MONO (1000 1975);
DISPLAY INVISIBLE (1000 1975);
FORCEPROP 0 LAST CDS_SEC 1
J 0
(1200 1900);
DISPLAY 1.021277 (1200 1900);
DISPLAY INVISIBLE (1200 1900);
FORCEPROP 1 LASTPIN (950 1950) $PN 1
J 0
(960 1930);
DISPLAY 0.489362 (960 1930);
PAINT MONO (960 1930);
FORCEPROP 1 LASTPIN (950 1750) $PN 2
J 0
(960 1730);
DISPLAY 0.489362 (960 1730);
PAINT MONO (960 1730);
FORCEPROP 1 LAST PACK_TYPE 0402
J 0
(1000 1650);
DISPLAY 0.489362 (1000 1650);
PAINT SKYBLUE (1000 1650);
FORCEPROP 1 LAST VOLTAGE 25V
J 0
(1000 1850);
DISPLAY 0.489362 (1000 1850);
PAINT SKYBLUE (1000 1850);
FORCEPROP 1 LAST VALUE 0.1UF
J 0
(1000 1900);
DISPLAY 0.489362 (1000 1900);
PAINT SKYBLUE (1000 1900);
FORCEPROP 1 LAST TOLERANCE 10%
J 0
(1000 1800);
DISPLAY 0.489362 (1000 1800);
PAINT SKYBLUE (1000 1800);
FORCEPROP 1 LAST MATERIAL X7R
J 0
(1000 1750);
DISPLAY 0.489362 (1000 1750);
PAINT SKYBLUE (1000 1750);
FORCEPROP 2 LAST CDS_LIB pure_quanta
J 0
(950 1850);
DISPLAY INVISIBLE (950 1850);
FORCEPROP 1 LAST PATH I2
J 0
(1000 2000);
DISPLAY 0.978723 (1000 2000);
PAINT WHITE (1000 2000);
DISPLAY INVISIBLE (1000 2000);
FORCEPROP 1 LAST PART_NUMBER CH4104K1B00
J 0
(1000 1700);
DISPLAY 0.489362 (1000 1700);
PAINT SKYBLUE (1000 1700);
DISPLAY INVISIBLE (1000 1700);
FORCEADD Q_CAP..1
(2250 3225);
FORCEPROP 1 LAST LOCATION PC113_C1P0_6
J 0
(2300 3325);
DISPLAY 0.489362 (2300 3325);
PAINT SKYBLUE (2300 3325);
FORCEPROP 0 LAST $SEC 1
J 0
(2300 3375);
DISPLAY 0.680851 (2300 3375);
PAINT MONO (2300 3375);
DISPLAY INVISIBLE (2300 3375);
FORCEPROP 0 LAST CDS_SEC 1
J 0
(2300 3375);
DISPLAY 1.021277 (2300 3375);
DISPLAY INVISIBLE (2300 3375);
FORCEPROP 1 LASTPIN (2250 3325) $PN 1
J 0
(2260 3305);
DISPLAY 0.489362 (2260 3305);
PAINT MONO (2260 3305);
FORCEPROP 1 LASTPIN (2250 3125) $PN 2
J 0
(2260 3105);
DISPLAY 0.489362 (2260 3105);
PAINT MONO (2260 3105);
FORCEPROP 1 LAST PACK_TYPE C0402
J 0
(2300 3025);
DISPLAY 0.489362 (2300 3025);
PAINT SKYBLUE (2300 3025);
FORCEPROP 1 LAST VALUE 2.2UF
J 0
(2300 3275);
DISPLAY 0.489362 (2300 3275);
PAINT SKYBLUE (2300 3275);
FORCEPROP 1 LAST VOLTAGE 10V
J 0
(2300 3225);
DISPLAY 0.489362 (2300 3225);
PAINT SKYBLUE (2300 3225);
FORCEPROP 1 LAST TOLERANCE 10%
J 0
(2300 3175);
DISPLAY 0.489362 (2300 3175);
PAINT SKYBLUE (2300 3175);
FORCEPROP 1 LAST MATERIAL X6S
J 0
(2300 3125);
DISPLAY 0.489362 (2300 3125);
PAINT SKYBLUE (2300 3125);
FORCEPROP 2 LAST CDS_LIB pure_quanta
J 0
(2250 3225);
DISPLAY INVISIBLE (2250 3225);
FORCEPROP 1 LAST PATH I20
J 0
(2300 3375);
DISPLAY 0.978723 (2300 3375);
PAINT WHITE (2300 3375);
DISPLAY INVISIBLE (2300 3375);
FORCEPROP 1 LAST PART_NUMBER CH5222KEB01
J 0
(2300 3075);
DISPLAY 0.489362 (2300 3075);
PAINT SKYBLUE (2300 3075);
DISPLAY INVISIBLE (2300 3075);
FORCEADD UNIVERSAL_GND..1
(2250 2950);
FORCEPROP 3 LASTPIN (2250 3000) SIG_NAME GND\g
J 0
(2260 3010);
DISPLAY 0.659574 (2260 3010);
PAINT MONO (2260 3010);
DISPLAY INVISIBLE (2260 3010);
FORCEPROP 2 LAST CDS_LIB pure_quanta_power
J 0
(2250 2950);
DISPLAY INVISIBLE (2250 2950);
FORCEPROP 1 LAST HDL_POWER GND
J 1
(2275 2875);
DISPLAY 0.872340 (2275 2875);
PAINT GREEN (2275 2875);
DISPLAY INVISIBLE (2275 2875);
FORCEPROP 1 LAST PATH I21
J 0
(2325 2950);
DISPLAY 0.872340 (2325 2950);
PAINT AQUA (2325 2950);
DISPLAY INVISIBLE (2325 2950);
FORCEADD ISL99390FRZTR5935..1
(3400 4875);
FORCEPROP 1 LAST LOCATION PU16
J 0
(3100 5750);
DISPLAY 0.489362 (3100 5750);
PAINT SKYBLUE (3100 5750);
FORCEPROP 0 LAST $SEC 1
J 0
(3100 5950);
DISPLAY 0.680851 (3100 5950);
PAINT MONO (3100 5950);
DISPLAY INVISIBLE (3100 5950);
FORCEPROP 2 LAST CDS_SEC 1
J 0
(3100 5925);
DISPLAY 1.021277 (3100 5925);
DISPLAY INVISIBLE (3100 5925);
FORCEPROP 0 LASTPIN (3800 4425) $PN 2
J 0
(3810 4435);
DISPLAY 0.489362 (3810 4435);
PAINT MONO (3810 4435);
FORCEPROP 0 LASTPIN (3800 5225) $PN 33
J 0
(3810 5235);
DISPLAY 0.489362 (3810 5235);
PAINT MONO (3810 5235);
FORCEPROP 0 LASTPIN (2950 4625) $PN 31
J 2
(2940 4635);
DISPLAY 0.489362 (2940 4635);
PAINT MONO (2940 4635);
FORCEPROP 0 LASTPIN (2950 5025) $PN 35
J 2
(2940 5035);
DISPLAY 0.489362 (2940 5035);
PAINT MONO (2940 5035);
FORCEPROP 0 LASTPIN (3800 4575) $PN 6
J 0
(3810 4585);
DISPLAY 0.489362 (3810 4585);
PAINT MONO (3810 4585);
FORCEPROP 0 LASTPIN (3800 4525) $PN 41
J 0
(3810 4535);
DISPLAY 0.489362 (3810 4535);
PAINT MONO (3810 4535);
FORCEPROP 0 LASTPIN (2950 4875) $PN 38
J 2
(2940 4885);
DISPLAY 0.489362 (2940 4885);
PAINT MONO (2940 4885);
FORCEPROP 0 LASTPIN (2950 4575) $PN 37
J 2
(2940 4585);
DISPLAY 0.489362 (2940 4585);
PAINT MONO (2940 4585);
FORCEPROP 0 LASTPIN (3800 4375) $PN 5
J 0
(3810 4385);
DISPLAY 0.489362 (3810 4385);
PAINT MONO (3810 4385);
FORCEPROP 0 LASTPIN (3800 4325) $PN 7_9-20_24
J 0
(3810 4335);
DISPLAY 0.489362 (3810 4335);
PAINT MONO (3810 4335);
FORCEPROP 0 LASTPIN (3800 4275) $PN 40
J 0
(3810 4285);
DISPLAY 0.489362 (3810 4285);
PAINT MONO (3810 4285);
FORCEPROP 0 LASTPIN (3800 4975) $PN 32
J 0
(3810 4985);
DISPLAY 0.489362 (3810 4985);
PAINT MONO (3810 4985);
FORCEPROP 0 LASTPIN (2950 5525) $PN 4
J 2
(2940 5535);
DISPLAY 0.489362 (2940 5535);
PAINT MONO (2940 5535);
FORCEPROP 0 LASTPIN (2950 4275) $PN 34
J 2
(2940 4285);
DISPLAY 0.489362 (2940 4285);
PAINT MONO (2940 4285);
FORCEPROP 0 LASTPIN (2950 4775) $PN 39
J 2
(2940 4785);
DISPLAY 0.489362 (2940 4785);
PAINT MONO (2940 4785);
FORCEPROP 0 LASTPIN (3800 4875) $PN 10_19
J 0
(3810 4885);
DISPLAY 0.489362 (3810 4885);
PAINT MONO (3810 4885);
FORCEPROP 0 LASTPIN (2950 4375) $PN 36
J 2
(2940 4385);
DISPLAY 0.489362 (2940 4385);
PAINT MONO (2940 4385);
FORCEPROP 0 LASTPIN (2950 5225) $PN 3
J 2
(2940 5235);
DISPLAY 0.489362 (2940 5235);
PAINT MONO (2940 5235);
FORCEPROP 0 LASTPIN (3800 5525) $PN 25_29
J 0
(3810 5535);
DISPLAY 0.489362 (3810 5535);
PAINT MONO (3810 5535);
FORCEPROP 0 LASTPIN (3800 5475) $PN 30
J 0
(3810 5485);
DISPLAY 0.489362 (3810 5485);
PAINT MONO (3810 5485);
FORCEPROP 0 LASTPIN (3800 4625) $PN 1
J 0
(3810 4635);
DISPLAY 0.489362 (3810 4635);
PAINT MONO (3810 4635);
FORCEPROP 2 LAST VALUE ISL99390FRZ-TR5935
J 0
(3100 5850);
DISPLAY 0.489362 (3100 5850);
PAINT SKYBLUE (3100 5850);
FORCEPROP 1 LAST MATERIAL IC
J 0
(3100 5600);
DISPLAY 0.489362 (3100 5600);
PAINT SKYBLUE (3100 5600);
FORCEPROP 2 LAST PART_TYPE SMLF
J 0
(3100 5900);
DISPLAY 0.638298 (3100 5900);
FORCEPROP 1 LAST NEEDS_NO_SIZE TRUE
J 0
(3400 4875);
DISPLAY 0.723404 (3400 4875);
PAINT GREEN (3400 4875);
DISPLAY INVISIBLE (3400 4875);
FORCEPROP 1 LAST CDS_LMAN_SYM_OUTLINE -300,700,250,-650
J 0
(3400 4875);
DISPLAY 0.468085 (3400 4875);
PAINT GREEN (3400 4875);
DISPLAY INVISIBLE (3400 4875);
FORCEPROP 2 LAST CDS_LIB pure_quanta
J 0
(3400 4875);
DISPLAY INVISIBLE (3400 4875);
FORCEPROP 1 LAST PATH I22
J 0
(3400 4875);
DISPLAY 0.723404 (3400 4875);
PAINT GREEN (3400 4875);
DISPLAY INVISIBLE (3400 4875);
FORCEPROP 1 LAST PART_NUMBER AL099390004
J 0
(3100 5675);
DISPLAY 0.489362 (3100 5675);
PAINT SKYBLUE (3100 5675);
DISPLAY INVISIBLE (3100 5675);
FORCEADD UNIVERSAL_GND..1
(4050 4150);
FORCEPROP 3 LASTPIN (4050 4200) SIG_NAME GND\g
J 0
(4060 4210);
DISPLAY 0.659574 (4060 4210);
PAINT MONO (4060 4210);
DISPLAY INVISIBLE (4060 4210);
FORCEPROP 2 LAST CDS_LIB pure_quanta_power
J 0
(4050 4150);
PAINT MONO (4050 4150);
DISPLAY INVISIBLE (4050 4150);
FORCEPROP 1 LAST HDL_POWER GND
J 1
(4075 4075);
DISPLAY 0.872340 (4075 4075);
PAINT GREEN (4075 4075);
DISPLAY INVISIBLE (4075 4075);
FORCEPROP 1 LAST PATH I23
J 0
(4125 4150);
DISPLAY 0.872340 (4125 4150);
PAINT AQUA (4125 4150);
DISPLAY INVISIBLE (4125 4150);
FORCEADD OFFPAGE..1
(1950 4775);
FORCEPROP 2 LAST $XR5 206 
J 0
(1098 4775);
DISPLAY 0.638298 (1098 4775);
PAINT MONO (1098 4775);
FORCEPROP 2 LAST $XR4 205 
J 0
(1218 4775);
DISPLAY 0.638298 (1218 4775);
PAINT MONO (1218 4775);
FORCEPROP 2 LAST $XR3 203 
J 0
(1338 4775);
DISPLAY 0.638298 (1338 4775);
PAINT MONO (1338 4775);
FORCEPROP 2 LAST $XR2 202 
J 0
(1458 4775);
DISPLAY 0.638298 (1458 4775);
PAINT MONO (1458 4775);
FORCEPROP 2 LAST $XR1 201 
J 0
(1578 4775);
DISPLAY 0.638298 (1578 4775);
PAINT MONO (1578 4775);
FORCEPROP 2 LAST $XR0 200 
J 0
(1698 4775);
DISPLAY 0.638298 (1698 4775);
PAINT MONO (1698 4775);
FORCEPROP 2 LAST CDS_LIB standard
J 0
(1950 4775);
DISPLAY INVISIBLE (1950 4775);
FORCEPROP 1 LAST OFFPAGE TRUE
J 0
(2275 4650);
DISPLAY 0.872340 (2275 4650);
PAINT GREEN (2275 4650);
DISPLAY INVISIBLE (2275 4650);
FORCEPROP 1 LAST COMMENT_BODY TRUE
J 0
(2075 4675);
DISPLAY 0.872340 (2075 4675);
PAINT GREEN (2075 4675);
DISPLAY INVISIBLE (2075 4675);
FORCEPROP 2 LAST PATH I24
J 0
(1700 4825);
DISPLAY 0.680851 (1700 4825);
DISPLAY INVISIBLE (1700 4825);
FORCEADD OFFPAGE..5
(1950 4875);
FORCEPROP 2 LAST $XR0 200 
J 0
(1695 4875);
DISPLAY 0.638298 (1695 4875);
PAINT MONO (1695 4875);
FORCEPROP 2 LAST CDS_LIB standard
J 0
(1950 4875);
DISPLAY INVISIBLE (1950 4875);
FORCEPROP 1 LAST OFFPAGE TRUE
J 0
(2275 4750);
DISPLAY 0.872340 (2275 4750);
PAINT GREEN (2275 4750);
DISPLAY INVISIBLE (2275 4750);
FORCEPROP 1 LAST COMMENT_BODY TRUE
J 0
(2050 4800);
DISPLAY 0.872340 (2050 4800);
PAINT GREEN (2050 4800);
DISPLAY INVISIBLE (2050 4800);
FORCEPROP 2 LAST PATH I25
J 0
(1675 4925);
DISPLAY 0.680851 (1675 4925);
DISPLAY INVISIBLE (1675 4925);
FORCEADD UNIVERSAL_GND..1
(1925 5100);
FORCEPROP 3 LASTPIN (1925 5150) SIG_NAME GND\g
J 0
(1935 5160);
DISPLAY 0.659574 (1935 5160);
PAINT MONO (1935 5160);
DISPLAY INVISIBLE (1935 5160);
FORCEPROP 2 LAST CDS_LIB pure_quanta_power
J 0
(1925 5100);
DISPLAY INVISIBLE (1925 5100);
FORCEPROP 1 LAST HDL_POWER GND
J 1
(1950 5025);
DISPLAY 0.872340 (1950 5025);
PAINT GREEN (1950 5025);
DISPLAY INVISIBLE (1950 5025);
FORCEPROP 1 LAST PATH I26
J 0
(2000 5100);
DISPLAY 0.872340 (2000 5100);
PAINT AQUA (2000 5100);
DISPLAY INVISIBLE (2000 5100);
FORCEADD Q_CAP..1
(1925 5300);
FORCEPROP 1 LAST LOCATION PC131
J 0
(1975 5400);
DISPLAY 0.489362 (1975 5400);
PAINT SKYBLUE (1975 5400);
FORCEPROP 0 LAST $SEC 1
J 0
(1975 5450);
DISPLAY 0.680851 (1975 5450);
PAINT MONO (1975 5450);
DISPLAY INVISIBLE (1975 5450);
FORCEPROP 0 LAST CDS_SEC 1
J 0
(1975 5450);
DISPLAY 1.021277 (1975 5450);
DISPLAY INVISIBLE (1975 5450);
FORCEPROP 1 LASTPIN (1925 5400) $PN 1
J 0
(1935 5380);
DISPLAY 0.489362 (1935 5380);
PAINT MONO (1935 5380);
FORCEPROP 1 LASTPIN (1925 5200) $PN 2
J 0
(1935 5180);
DISPLAY 0.489362 (1935 5180);
PAINT MONO (1935 5180);
FORCEPROP 1 LAST PACK_TYPE C0402
J 0
(1975 5100);
DISPLAY 0.489362 (1975 5100);
PAINT SKYBLUE (1975 5100);
FORCEPROP 1 LAST VOLTAGE 10V
J 0
(1975 5300);
DISPLAY 0.489362 (1975 5300);
PAINT SKYBLUE (1975 5300);
FORCEPROP 1 LAST VALUE 2.2UF
J 0
(1975 5350);
DISPLAY 0.489362 (1975 5350);
PAINT SKYBLUE (1975 5350);
FORCEPROP 1 LAST TOLERANCE 10%
J 0
(1975 5250);
DISPLAY 0.489362 (1975 5250);
PAINT SKYBLUE (1975 5250);
FORCEPROP 1 LAST MATERIAL X6S
J 0
(1975 5200);
DISPLAY 0.489362 (1975 5200);
PAINT SKYBLUE (1975 5200);
FORCEPROP 2 LAST CDS_LIB pure_quanta
J 0
(1925 5300);
DISPLAY INVISIBLE (1925 5300);
FORCEPROP 1 LAST PATH I27
J 0
(1975 5450);
DISPLAY 0.978723 (1975 5450);
PAINT WHITE (1975 5450);
DISPLAY INVISIBLE (1975 5450);
FORCEPROP 1 LAST PART_NUMBER CH5222KEB01
J 0
(1975 5150);
DISPLAY 0.489362 (1975 5150);
PAINT SKYBLUE (1975 5150);
DISPLAY INVISIBLE (1975 5150);
FORCEADD Q_RES..2
(1925 5850);
FORCEPROP 1 LAST LOCATION PR94
J 0
(1970 5975);
DISPLAY 0.489362 (1970 5975);
PAINT SKYBLUE (1970 5975);
FORCEPROP 0 LAST $SEC 1
J 0
(1975 6025);
DISPLAY 0.680851 (1975 6025);
PAINT MONO (1975 6025);
DISPLAY INVISIBLE (1975 6025);
FORCEPROP 0 LAST CDS_SEC 1
J 0
(1975 6025);
DISPLAY 1.021277 (1975 6025);
DISPLAY INVISIBLE (1975 6025);
FORCEPROP 1 LASTPIN (1925 5950) $PN 1
J 0
(1930 5912);
DISPLAY 0.489362 (1930 5912);
PAINT MONO (1930 5912);
FORCEPROP 1 LASTPIN (1925 5750) $PN 2
J 0
(1930 5760);
DISPLAY 0.489362 (1930 5760);
PAINT MONO (1930 5760);
FORCEPROP 1 LAST WATTAGE 1/16W
J 0
(1975 5825);
DISPLAY 0.489362 (1975 5825);
PAINT SKYBLUE (1975 5825);
FORCEPROP 1 LAST MATERIAL CHIP
J 0
(1975 5775);
DISPLAY 0.489362 (1975 5775);
PAINT SKYBLUE (1975 5775);
FORCEPROP 1 LAST TOLERANCE 1%
J 0
(1975 5875);
DISPLAY 0.489362 (1975 5875);
PAINT SKYBLUE (1975 5875);
FORCEPROP 1 LAST VALUE 2.2
J 0
(1975 5925);
DISPLAY 0.489362 (1975 5925);
PAINT SKYBLUE (1975 5925);
FORCEPROP 1 LAST PACK_TYPE 0402LF
J 0
(1975 5675);
DISPLAY 0.489362 (1975 5675);
PAINT SKYBLUE (1975 5675);
FORCEPROP 2 LAST CDS_LIB pure_quanta
J 0
(1925 5850);
DISPLAY INVISIBLE (1925 5850);
FORCEPROP 1 LAST PATH I28
J 0
(1975 6025);
DISPLAY 0.978723 (1975 6025);
PAINT WHITE (1975 6025);
DISPLAY INVISIBLE (1975 6025);
FORCEPROP 1 LAST PART_NUMBER CS-2202FB01
J 0
(1975 5725);
DISPLAY 0.489362 (1975 5725);
PAINT SKYBLUE (1975 5725);
DISPLAY INVISIBLE (1975 5725);
FORCEADD VCC_CORE..1
(1925 6275);
FORCEPROP 3 LASTPIN (1925 6225) SIG_NAME PVDDCR_CPU1_P0_PVCC\g
J 0
(1935 6235);
DISPLAY 0.659574 (1935 6235);
PAINT MONO (1935 6235);
DISPLAY INVISIBLE (1935 6235);
FORCEPROP 1 LAST HDL_POWER PVDDCR_CPU1_P0_PVCC
J 1
(1925 6325);
DISPLAY 0.489362 (1925 6325);
PAINT GREEN (1925 6325);
FORCEPROP 2 LAST CDS_LIB pure_quanta_power
J 0
(1925 6275);
DISPLAY INVISIBLE (1925 6275);
FORCEPROP 1 LAST PATH I29
J 0
(1975 6300);
DISPLAY 0.872340 (1975 6300);
PAINT AQUA (1975 6300);
DISPLAY INVISIBLE (1975 6300);
FORCEADD UNIVERSAL_GND..1
(1450 1500);
FORCEPROP 3 LASTPIN (1450 1550) SIG_NAME GND\g
J 0
(1460 1560);
DISPLAY 0.659574 (1460 1560);
PAINT MONO (1460 1560);
DISPLAY INVISIBLE (1460 1560);
FORCEPROP 2 LAST CDS_LIB pure_quanta_power
J 0
(1450 1500);
PAINT MONO (1450 1500);
DISPLAY INVISIBLE (1450 1500);
FORCEPROP 1 LAST HDL_POWER GND
J 1
(1475 1425);
DISPLAY 0.872340 (1475 1425);
PAINT GREEN (1475 1425);
DISPLAY INVISIBLE (1475 1425);
FORCEPROP 1 LAST PATH I3
J 0
(1525 1500);
DISPLAY 0.872340 (1525 1500);
PAINT AQUA (1525 1500);
DISPLAY INVISIBLE (1525 1500);
FORCEADD UNIVERSAL_GND..1
(2275 5600);
FORCEPROP 3 LASTPIN (2275 5650) SIG_NAME GND\g
J 0
(2285 5660);
DISPLAY 0.659574 (2285 5660);
PAINT MONO (2285 5660);
DISPLAY INVISIBLE (2285 5660);
FORCEPROP 2 LAST CDS_LIB pure_quanta_power
J 0
(2275 5600);
DISPLAY INVISIBLE (2275 5600);
FORCEPROP 1 LAST HDL_POWER GND
J 1
(2300 5525);
DISPLAY 0.872340 (2300 5525);
PAINT GREEN (2300 5525);
DISPLAY INVISIBLE (2300 5525);
FORCEPROP 1 LAST PATH I30
J 0
(2350 5600);
DISPLAY 0.872340 (2350 5600);
PAINT AQUA (2350 5600);
DISPLAY INVISIBLE (2350 5600);
FORCEADD Q_CAP..1
(2275 5875);
FORCEPROP 1 LAST LOCATION PC133_C1P0_5
J 0
(2325 5975);
DISPLAY 0.489362 (2325 5975);
PAINT SKYBLUE (2325 5975);
FORCEPROP 0 LAST $SEC 1
J 0
(2325 6025);
DISPLAY 0.680851 (2325 6025);
PAINT MONO (2325 6025);
DISPLAY INVISIBLE (2325 6025);
FORCEPROP 0 LAST CDS_SEC 1
J 0
(2325 6025);
DISPLAY 1.021277 (2325 6025);
DISPLAY INVISIBLE (2325 6025);
FORCEPROP 1 LASTPIN (2275 5975) $PN 1
J 0
(2285 5955);
DISPLAY 0.489362 (2285 5955);
PAINT MONO (2285 5955);
FORCEPROP 1 LASTPIN (2275 5775) $PN 2
J 0
(2285 5755);
DISPLAY 0.489362 (2285 5755);
PAINT MONO (2285 5755);
FORCEPROP 1 LAST PACK_TYPE C0402
J 0
(2325 5675);
DISPLAY 0.489362 (2325 5675);
PAINT SKYBLUE (2325 5675);
FORCEPROP 1 LAST VOLTAGE 10V
J 0
(2325 5875);
DISPLAY 0.489362 (2325 5875);
PAINT SKYBLUE (2325 5875);
FORCEPROP 1 LAST VALUE 2.2UF
J 0
(2325 5925);
DISPLAY 0.489362 (2325 5925);
PAINT SKYBLUE (2325 5925);
FORCEPROP 1 LAST TOLERANCE 10%
J 0
(2325 5825);
DISPLAY 0.489362 (2325 5825);
PAINT SKYBLUE (2325 5825);
FORCEPROP 1 LAST MATERIAL X6S
J 0
(2325 5775);
DISPLAY 0.489362 (2325 5775);
PAINT SKYBLUE (2325 5775);
FORCEPROP 2 LAST CDS_LIB pure_quanta
J 0
(2275 5875);
DISPLAY INVISIBLE (2275 5875);
FORCEPROP 1 LAST PATH I31
J 0
(2325 6025);
DISPLAY 0.978723 (2325 6025);
PAINT WHITE (2325 6025);
DISPLAY INVISIBLE (2325 6025);
FORCEPROP 1 LAST PART_NUMBER CH5222KEB01
J 0
(2325 5725);
DISPLAY 0.489362 (2325 5725);
PAINT SKYBLUE (2325 5725);
DISPLAY INVISIBLE (2325 5725);
FORCEADD UNIVERSAL_GND..1
(4800 1250);
FORCEPROP 3 LASTPIN (4800 1300) SIG_NAME GND\g
J 0
(4810 1310);
DISPLAY 0.659574 (4810 1310);
PAINT MONO (4810 1310);
DISPLAY INVISIBLE (4810 1310);
FORCEPROP 2 LAST CDS_LIB pure_quanta_power
J 0
(4800 1250);
DISPLAY INVISIBLE (4800 1250);
FORCEPROP 1 LAST HDL_POWER GND
J 1
(4825 1175);
DISPLAY 0.872340 (4825 1175);
PAINT GREEN (4825 1175);
DISPLAY INVISIBLE (4825 1175);
FORCEPROP 1 LAST PATH I32
J 0
(4875 1250);
DISPLAY 0.872340 (4875 1250);
PAINT AQUA (4875 1250);
DISPLAY INVISIBLE (4875 1250);
FORCEADD Q_RES..2
(4800 1475);
FORCEPROP 1 LAST LOCATION PR155
J 0
(4845 1600);
DISPLAY 0.489362 (4845 1600);
PAINT SKYBLUE (4845 1600);
FORCEPROP 0 LAST $SEC 1
J 0
(4850 1650);
DISPLAY 0.680851 (4850 1650);
PAINT MONO (4850 1650);
DISPLAY INVISIBLE (4850 1650);
FORCEPROP 0 LAST CDS_SEC 1
J 0
(4850 1650);
DISPLAY 1.021277 (4850 1650);
DISPLAY INVISIBLE (4850 1650);
FORCEPROP 1 LASTPIN (4800 1575) $PN 1
J 0
(4805 1537);
DISPLAY 0.489362 (4805 1537);
PAINT MONO (4805 1537);
FORCEPROP 1 LASTPIN (4800 1375) $PN 2
J 0
(4805 1385);
DISPLAY 0.489362 (4805 1385);
PAINT MONO (4805 1385);
FORCEPROP 1 LAST MATERIAL EMPTY
J 0
(4840 1400);
DISPLAY 0.489362 (4840 1400);
PAINT RED (4840 1400);
FORCEPROP 1 LAST PACK_TYPE 0402LF
J 0
(4840 1300);
DISPLAY 0.489362 (4840 1300);
PAINT SKYBLUE (4840 1300);
FORCEPROP 1 LAST VALUE 1.5
J 0
(4845 1550);
DISPLAY 0.489362 (4845 1550);
PAINT SKYBLUE (4845 1550);
FORCEPROP 1 LAST WATTAGE 1/8W
J 0
(4840 1450);
DISPLAY 0.489362 (4840 1450);
PAINT SKYBLUE (4840 1450);
FORCEPROP 1 LAST TOLERANCE 1%
J 0
(4845 1500);
DISPLAY 0.489362 (4845 1500);
PAINT SKYBLUE (4845 1500);
FORCEPROP 2 LAST CDS_LIB pure_quanta
J 0
(4800 1475);
DISPLAY INVISIBLE (4800 1475);
FORCEPROP 1 LAST PATH I33
J 0
(4850 1650);
DISPLAY 0.978723 (4850 1650);
PAINT WHITE (4850 1650);
DISPLAY INVISIBLE (4850 1650);
FORCEPROP 1 LAST PART_NUMBER CS-1504FB00
J 0
(4840 1350);
DISPLAY 0.489362 (4840 1350);
PAINT SKYBLUE (4840 1350);
DISPLAY INVISIBLE (4840 1350);
FORCEADD UNIVERSAL_GND..1
(5150 1875);
FORCEPROP 3 LASTPIN (5150 1925) SIG_NAME GND\g
J 0
(5160 1935);
DISPLAY 0.659574 (5160 1935);
PAINT MONO (5160 1935);
DISPLAY INVISIBLE (5160 1935);
FORCEPROP 2 LAST CDS_LIB pure_quanta_power
J 0
(5150 1875);
DISPLAY INVISIBLE (5150 1875);
FORCEPROP 1 LAST HDL_POWER GND
J 1
(5175 1800);
DISPLAY 0.872340 (5175 1800);
PAINT GREEN (5175 1800);
DISPLAY INVISIBLE (5175 1800);
FORCEPROP 1 LAST PATH I34
J 0
(5225 1875);
DISPLAY 0.872340 (5225 1875);
PAINT AQUA (5225 1875);
DISPLAY INVISIBLE (5225 1875);
FORCEADD Q_RES..1
(5975 1100);
FORCEPROP 1 LAST LOCATION PR421
J 0
(5925 1125);
DISPLAY 0.489362 (5925 1125);
PAINT SKYBLUE (5925 1125);
FORCEPROP 0 LAST $SEC 1
J 0
(6225 1250);
DISPLAY 0.680851 (6225 1250);
PAINT MONO (6225 1250);
DISPLAY INVISIBLE (6225 1250);
FORCEPROP 0 LAST CDS_SEC 1
J 0
(6225 1250);
DISPLAY 1.021277 (6225 1250);
DISPLAY INVISIBLE (6225 1250);
FORCEPROP 1 LASTPIN (5875 1100) $PN 1
J 0
(5887 1112);
DISPLAY 0.489362 (5887 1112);
PAINT MONO (5887 1112);
FORCEPROP 1 LASTPIN (6075 1100) $PN 2
J 0
(6037 1112);
DISPLAY 0.489362 (6037 1112);
PAINT MONO (6037 1112);
FORCEPROP 1 LAST WATTAGE 1/16W
J 2
(6225 1175);
DISPLAY 0.489362 (6225 1175);
PAINT SKYBLUE (6225 1175);
FORCEPROP 1 LAST MATERIAL CHIP
J 0
(6125 1125);
DISPLAY 0.489362 (6125 1125);
PAINT SKYBLUE (6125 1125);
FORCEPROP 1 LAST TOLERANCE 5%
J 0
(5800 1125);
DISPLAY 0.489362 (5800 1125);
PAINT SKYBLUE (5800 1125);
FORCEPROP 1 LAST VALUE 0
J 2
(5775 1125);
DISPLAY 0.489362 (5775 1125);
PAINT SKYBLUE (5775 1125);
FORCEPROP 1 LAST PACK_TYPE 0402LF
J 0
(6100 1050);
DISPLAY 0.489362 (6100 1050);
PAINT SKYBLUE (6100 1050);
FORCEPROP 2 LAST CDS_LIB pure_quanta
J 0
(5975 1100);
DISPLAY INVISIBLE (5975 1100);
FORCEPROP 1 LAST PATH I35
J 0
(5925 1250);
DISPLAY 0.978723 (5925 1250);
PAINT WHITE (5925 1250);
DISPLAY INVISIBLE (5925 1250);
FORCEPROP 1 LAST PART_NUMBER CS00002JB13
J 0
(5675 1050);
DISPLAY 0.489362 (5675 1050);
PAINT SKYBLUE (5675 1050);
DISPLAY INVISIBLE (5675 1050);
FORCEADD Q_INDUCTOR..1
R 2
(5325 2000);
FORCEPROP 1 LAST LOCATION PL9
J 0
(5175 2150);
DISPLAY 0.489362 (5175 2150);
PAINT SKYBLUE (5175 2150);
FORCEPROP 0 LAST $SEC 1
J 0
(5175 2175);
DISPLAY 0.680851 (5175 2175);
PAINT MONO (5175 2175);
DISPLAY INVISIBLE (5175 2175);
FORCEPROP 0 LAST CDS_SEC 1
J 0
(5175 2175);
DISPLAY 0.680851 (5175 2175);
DISPLAY INVISIBLE (5175 2175);
FORCEPROP 0 LASTPIN (5425 1975) $PN 1
J 0
(5435 1985);
DISPLAY 0.489362 (5435 1985);
PAINT MONO (5435 1985);
FORCEPROP 0 LASTPIN (5225 1975) $PN 2
J 2
(5215 1985);
DISPLAY 0.489362 (5215 1985);
PAINT MONO (5215 1985);
FORCEPROP 2 LASTPIN (5425 1975) SIG_NAME IND_CPU1_P0_CPL0
J 0
(5440 1985);
DISPLAY 0.489362 (5440 1985);
FORCEPROP 2 LASTPROP $XRERR UNIQUE?
J 0
(5200 1985);
DISPLAY 0.638298 (5200 1985);
PAINT MONO (5200 1985);
DISPLAY INVISIBLE (5200 1985);
FORCEPROP 2 LAST VALUE 120NH/69A
J 0
(5175 2125);
DISPLAY 0.489362 (5175 2125);
PAINT SKYBLUE (5175 2125);
FORCEPROP 1 LAST MATERIAL IND
J 0
(5175 2050);
DISPLAY 0.489362 (5175 2050);
PAINT SKYBLUE (5175 2050);
FORCEPROP 2 LAST PACK_TYPE SMLF
J 0
(5175 2100);
DISPLAY 0.489362 (5175 2100);
PAINT SKYBLUE (5175 2100);
FORCEPROP 2 LAST CDS_LIB pure_quanta
J 0
(5325 2000);
DISPLAY INVISIBLE (5325 2000);
FORCEPROP 1 LAST NEEDS_NO_SIZE TRUE
J 2
(5325 2000);
DISPLAY 0.468085 (5325 2000);
PAINT GREEN (5325 2000);
DISPLAY INVISIBLE (5325 2000);
FORCEPROP 1 LAST PATH I36
J 2
(5250 2055);
DISPLAY 0.723404 (5250 2055);
PAINT GREEN (5250 2055);
DISPLAY INVISIBLE (5250 2055);
FORCEPROP 1 LAST PART_NUMBER CV+12^0EZ03
J 0
(5175 2075);
DISPLAY 0.489362 (5175 2075);
PAINT SKYBLUE (5175 2075);
DISPLAY INVISIBLE (5175 2075);
FORCEADD Q_CAP..1
(5350 2450);
FORCEPROP 1 LAST LOCATION PC117
J 0
(5400 2550);
DISPLAY 0.489362 (5400 2550);
PAINT SKYBLUE (5400 2550);
FORCEPROP 0 LAST $SEC 1
J 0
(5400 2600);
DISPLAY 0.680851 (5400 2600);
PAINT MONO (5400 2600);
DISPLAY INVISIBLE (5400 2600);
FORCEPROP 0 LAST CDS_SEC 1
J 2
(5400 2575);
DISPLAY 1.021277 (5400 2575);
DISPLAY INVISIBLE (5400 2575);
FORCEPROP 1 LASTPIN (5350 2550) $PN 1
J 0
(5360 2530);
DISPLAY 0.489362 (5360 2530);
PAINT MONO (5360 2530);
FORCEPROP 1 LASTPIN (5350 2350) $PN 2
J 0
(5360 2330);
DISPLAY 0.489362 (5360 2330);
PAINT MONO (5360 2330);
FORCEPROP 1 LAST PACK_TYPE 0402
J 0
(5400 2250);
DISPLAY 0.489362 (5400 2250);
PAINT SKYBLUE (5400 2250);
FORCEPROP 1 LAST MATERIAL X7R
J 0
(5400 2350);
DISPLAY 0.489362 (5400 2350);
PAINT SKYBLUE (5400 2350);
FORCEPROP 1 LAST TOLERANCE 10%
J 0
(5400 2400);
DISPLAY 0.489362 (5400 2400);
PAINT SKYBLUE (5400 2400);
FORCEPROP 1 LAST VOLTAGE 16V
J 0
(5400 2450);
DISPLAY 0.489362 (5400 2450);
PAINT SKYBLUE (5400 2450);
FORCEPROP 1 LAST VALUE 0.22UF
J 0
(5400 2500);
DISPLAY 0.489362 (5400 2500);
PAINT SKYBLUE (5400 2500);
FORCEPROP 2 LAST CDS_LIB pure_quanta
J 2
(5350 2450);
DISPLAY INVISIBLE (5350 2450);
FORCEPROP 1 LAST PATH I37
J 0
(5400 2600);
DISPLAY 0.978723 (5400 2600);
PAINT WHITE (5400 2600);
DISPLAY INVISIBLE (5400 2600);
FORCEPROP 1 LAST PART_NUMBER CH4223K1B00
J 0
(5400 2300);
DISPLAY 0.489362 (5400 2300);
PAINT SKYBLUE (5400 2300);
DISPLAY INVISIBLE (5400 2300);
FORCEADD Q_INDUCTOR4P_14..1
(6300 2100);
FORCEPROP 1 LAST LOCATION PL7
J 0
(6100 2325);
DISPLAY 0.489362 (6100 2325);
PAINT SKYBLUE (6100 2325);
FORCEPROP 0 LAST $SEC 1
J 0
(6075 2400);
DISPLAY 0.680851 (6075 2400);
PAINT MONO (6075 2400);
DISPLAY INVISIBLE (6075 2400);
FORCEPROP 0 LAST CDS_SEC 1
J 0
(6075 2400);
DISPLAY 1.021277 (6075 2400);
DISPLAY INVISIBLE (6075 2400);
FORCEPROP 0 LASTPIN (5900 2225) $PN 1
J 2
(5890 2235);
DISPLAY 0.489362 (5890 2235);
PAINT MONO (5890 2235);
FORCEPROP 0 LASTPIN (5900 1975) $PN 2
J 2
(5890 1985);
DISPLAY 0.489362 (5890 1985);
PAINT MONO (5890 1985);
FORCEPROP 0 LASTPIN (6700 1975) $PN 3
J 0
(6710 1985);
DISPLAY 0.489362 (6710 1985);
PAINT MONO (6710 1985);
FORCEPROP 0 LASTPIN (6700 2225) $PN 4
J 0
(6710 2235);
DISPLAY 0.489362 (6710 2235);
PAINT MONO (6710 2235);
FORCEPROP 2 LAST PART_TYPE SMLF
J 0
(6225 1850);
DISPLAY 1.021277 (6225 1850);
FORCEPROP 2 LAST VALUE 150NH
J 0
(6200 2275);
DISPLAY 0.489362 (6200 2275);
PAINT SKYBLUE (6200 2275);
FORCEPROP 1 LAST MATERIAL IND
J 0
(6100 2275);
DISPLAY 0.489362 (6100 2275);
PAINT SKYBLUE (6100 2275);
FORCEPROP 2 LAST CDS_LIB pure_quanta
J 0
(6300 2100);
DISPLAY INVISIBLE (6300 2100);
FORCEPROP 1 LAST NEEDS_NO_SIZE TRUE
J 0
(6300 2100);
DISPLAY 0.468085 (6300 2100);
PAINT GREEN (6300 2100);
DISPLAY INVISIBLE (6300 2100);
FORCEPROP 1 LAST PATH I38
J 0
(6500 2255);
DISPLAY 0.723404 (6500 2255);
PAINT GREEN (6500 2255);
DISPLAY INVISIBLE (6500 2255);
FORCEPROP 1 LAST PART_NUMBER CV+15^0TZ04
J 0
(6350 2275);
DISPLAY 0.489362 (6350 2275);
PAINT SKYBLUE (6350 2275);
DISPLAY INVISIBLE (6350 2275);
FORCEADD Q_RES..1
(4625 2575);
FORCEPROP 1 LAST LOCATION PR420
J 0
(4400 2650);
DISPLAY 0.489362 (4400 2650);
PAINT SKYBLUE (4400 2650);
FORCEPROP 0 LAST $SEC 1
J 0
(4900 2675);
DISPLAY 0.680851 (4900 2675);
PAINT MONO (4900 2675);
DISPLAY INVISIBLE (4900 2675);
FORCEPROP 0 LAST CDS_SEC 1
J 0
(4900 2675);
DISPLAY 1.021277 (4900 2675);
DISPLAY INVISIBLE (4900 2675);
FORCEPROP 1 LASTPIN (4525 2575) $PN 1
J 0
(4537 2587);
DISPLAY 0.787234 (4537 2587);
PAINT MONO (4537 2587);
DISPLAY INVISIBLE (4537 2587);
FORCEPROP 1 LASTPIN (4725 2575) $PN 2
J 0
(4687 2587);
DISPLAY 0.787234 (4687 2587);
PAINT MONO (4687 2587);
DISPLAY INVISIBLE (4687 2587);
FORCEPROP 1 LAST VALUE 5.6
J 2
(4575 2650);
DISPLAY 0.489362 (4575 2650);
PAINT SKYBLUE (4575 2650);
FORCEPROP 1 LAST MATERIAL CHIP
J 0
(4475 2500);
DISPLAY 0.489362 (4475 2500);
PAINT SKYBLUE (4475 2500);
FORCEPROP 1 LAST WATTAGE 1/16W
J 2
(4900 2650);
DISPLAY 0.489362 (4900 2650);
PAINT SKYBLUE (4900 2650);
FORCEPROP 1 LAST PACK_TYPE 0402LF
J 0
(5025 2500);
DISPLAY 0.489362 (5025 2500);
PAINT SKYBLUE (5025 2500);
FORCEPROP 1 LAST TOLERANCE 1%
J 0
(4625 2650);
DISPLAY 0.489362 (4625 2650);
PAINT SKYBLUE (4625 2650);
FORCEPROP 2 LAST CDS_LIB pure_quanta
J 0
(4625 2575);
DISPLAY INVISIBLE (4625 2575);
FORCEPROP 1 LAST PATH I39
J 0
(4575 2725);
DISPLAY 0.978723 (4575 2725);
PAINT WHITE (4575 2725);
DISPLAY INVISIBLE (4575 2725);
FORCEPROP 1 LAST PART_NUMBER CS-5602FB01
J 0
(4650 2500);
DISPLAY 0.489362 (4650 2500);
PAINT SKYBLUE (4650 2500);
DISPLAY INVISIBLE (4650 2500);
FORCEADD Q_RES..2
R 2
(1450 1725);
FORCEPROP 1 LAST LOCATION PR7
J 2
(1405 1850);
DISPLAY 0.489362 (1405 1850);
PAINT SKYBLUE (1405 1850);
FORCEPROP 0 LAST $SEC 1
J 0
(1425 1900);
DISPLAY 0.680851 (1425 1900);
PAINT MONO (1425 1900);
DISPLAY INVISIBLE (1425 1900);
FORCEPROP 0 LAST CDS_SEC 1
J 0
(1425 1900);
DISPLAY 1.021277 (1425 1900);
DISPLAY INVISIBLE (1425 1900);
FORCEPROP 1 LASTPIN (1450 1825) $PN 1
J 2
(1445 1787);
DISPLAY 0.489362 (1445 1787);
PAINT MONO (1445 1787);
FORCEPROP 1 LASTPIN (1450 1625) $PN 2
J 2
(1445 1635);
DISPLAY 0.489362 (1445 1635);
PAINT MONO (1445 1635);
FORCEPROP 1 LAST WATTAGE 1/16W
J 2
(1410 1700);
DISPLAY 0.489362 (1410 1700);
PAINT SKYBLUE (1410 1700);
FORCEPROP 1 LAST MATERIAL EMPTY
J 2
(1410 1650);
DISPLAY 0.489362 (1410 1650);
PAINT RED (1410 1650);
FORCEPROP 1 LAST TOLERANCE 1%
J 2
(1405 1750);
DISPLAY 0.489362 (1405 1750);
PAINT SKYBLUE (1405 1750);
FORCEPROP 1 LAST VALUE 8.87K
J 2
(1405 1800);
DISPLAY 0.489362 (1405 1800);
PAINT SKYBLUE (1405 1800);
FORCEPROP 1 LAST PACK_TYPE 0402LF
J 2
(1410 1550);
DISPLAY 0.489362 (1410 1550);
PAINT SKYBLUE (1410 1550);
FORCEPROP 2 LAST CDS_LIB pure_quanta
J 2
(1450 1725);
DISPLAY INVISIBLE (1450 1725);
FORCEPROP 1 LAST PATH I4
J 2
(1400 1900);
DISPLAY 0.978723 (1400 1900);
PAINT WHITE (1400 1900);
DISPLAY INVISIBLE (1400 1900);
FORCEPROP 1 LAST PART_NUMBER CS28872FB01
J 2
(1410 1600);
DISPLAY 0.489362 (1410 1600);
PAINT SKYBLUE (1410 1600);
DISPLAY INVISIBLE (1410 1600);
FORCEADD Q_CAP..1
(4225 3125);
FORCEPROP 1 LAST LOCATION PC114_6
J 0
(4275 3275);
DISPLAY 0.489362 (4275 3275);
PAINT SKYBLUE (4275 3275);
FORCEPROP 0 LAST $SEC 1
J 0
(4275 3275);
DISPLAY 0.680851 (4275 3275);
PAINT MONO (4275 3275);
DISPLAY INVISIBLE (4275 3275);
FORCEPROP 0 LAST CDS_SEC 1
J 0
(4275 3275);
DISPLAY 1.021277 (4275 3275);
DISPLAY INVISIBLE (4275 3275);
FORCEPROP 1 LASTPIN (4225 3225) $PN 1
J 0
(4235 3205);
DISPLAY 0.489362 (4235 3205);
PAINT MONO (4235 3205);
FORCEPROP 1 LASTPIN (4225 3025) $PN 2
J 0
(4235 3005);
DISPLAY 0.489362 (4235 3005);
PAINT MONO (4235 3005);
FORCEPROP 1 LAST VOLTAGE 25V
J 0
(4275 3175);
DISPLAY 0.489362 (4275 3175);
PAINT SKYBLUE (4275 3175);
FORCEPROP 1 LAST VALUE 0.1UF
J 0
(4275 3225);
DISPLAY 0.489362 (4275 3225);
PAINT SKYBLUE (4275 3225);
FORCEPROP 1 LAST TOLERANCE 10%
J 0
(4275 3125);
DISPLAY 0.489362 (4275 3125);
PAINT SKYBLUE (4275 3125);
FORCEPROP 1 LAST MATERIAL X7R
J 0
(4275 3075);
DISPLAY 0.489362 (4275 3075);
PAINT SKYBLUE (4275 3075);
FORCEPROP 1 LAST PACK_TYPE 0402
J 0
(4275 2975);
DISPLAY 0.489362 (4275 2975);
PAINT SKYBLUE (4275 2975);
FORCEPROP 2 LAST CDS_LIB pure_quanta
J 0
(4225 3125);
DISPLAY INVISIBLE (4225 3125);
FORCEPROP 1 LAST PATH I40
J 0
(4275 3275);
DISPLAY 0.978723 (4275 3275);
PAINT WHITE (4275 3275);
DISPLAY INVISIBLE (4275 3275);
FORCEPROP 1 LAST PART_NUMBER CH4104K1B00
J 0
(4275 3025);
DISPLAY 0.489362 (4275 3025);
PAINT SKYBLUE (4275 3025);
DISPLAY INVISIBLE (4275 3025);
FORCEADD Q_CAP..1
(4650 3125);
FORCEPROP 1 LAST LOCATION PC115_6
J 0
(4700 3275);
DISPLAY 0.489362 (4700 3275);
PAINT SKYBLUE (4700 3275);
FORCEPROP 0 LAST $SEC 1
J 0
(4700 3325);
DISPLAY 0.680851 (4700 3325);
PAINT MONO (4700 3325);
DISPLAY INVISIBLE (4700 3325);
FORCEPROP 0 LAST CDS_SEC 1
J 0
(4700 3325);
DISPLAY 1.021277 (4700 3325);
DISPLAY INVISIBLE (4700 3325);
FORCEPROP 1 LASTPIN (4650 3225) $PN 1
J 0
(4660 3205);
DISPLAY 0.489362 (4660 3205);
PAINT MONO (4660 3205);
FORCEPROP 1 LASTPIN (4650 3025) $PN 2
J 0
(4660 3005);
DISPLAY 0.489362 (4660 3005);
PAINT MONO (4660 3005);
FORCEPROP 1 LAST PACK_TYPE C0402
J 0
(4700 3025);
DISPLAY 0.489362 (4700 3025);
PAINT SKYBLUE (4700 3025);
FORCEPROP 1 LAST VOLTAGE 25V
J 0
(4700 3175);
DISPLAY 0.489362 (4700 3175);
PAINT SKYBLUE (4700 3175);
FORCEPROP 1 LAST VALUE 1UF
J 0
(4700 3225);
DISPLAY 0.489362 (4700 3225);
PAINT SKYBLUE (4700 3225);
FORCEPROP 1 LAST TOLERANCE 10%
J 0
(4700 3125);
DISPLAY 0.489362 (4700 3125);
PAINT SKYBLUE (4700 3125);
FORCEPROP 1 LAST MATERIAL X6S
J 0
(4700 3075);
DISPLAY 0.489362 (4700 3075);
PAINT SKYBLUE (4700 3075);
FORCEPROP 2 LAST CDS_LIB pure_quanta
J 0
(4650 3125);
DISPLAY INVISIBLE (4650 3125);
FORCEPROP 1 LAST PATH I41
J 0
(4700 3275);
DISPLAY 0.978723 (4700 3275);
PAINT WHITE (4700 3275);
DISPLAY INVISIBLE (4700 3275);
FORCEPROP 1 LAST PART_NUMBER CH5104KEB02
J 0
(4700 2975);
DISPLAY 0.489362 (4700 2975);
PAINT SKYBLUE (4700 2975);
DISPLAY INVISIBLE (4700 2975);
FORCEADD Q_CAP..1
(5050 3125);
FORCEPROP 1 LAST LOCATION PC116_6
J 0
(5100 3275);
DISPLAY 0.489362 (5100 3275);
PAINT SKYBLUE (5100 3275);
FORCEPROP 0 LAST $SEC 1
J 0
(5100 3325);
DISPLAY 0.680851 (5100 3325);
PAINT MONO (5100 3325);
DISPLAY INVISIBLE (5100 3325);
FORCEPROP 0 LAST CDS_SEC 1
J 0
(5100 3325);
DISPLAY 1.021277 (5100 3325);
DISPLAY INVISIBLE (5100 3325);
FORCEPROP 1 LASTPIN (5050 3225) $PN 1
J 0
(5060 3205);
DISPLAY 0.489362 (5060 3205);
PAINT MONO (5060 3205);
FORCEPROP 1 LASTPIN (5050 3025) $PN 2
J 0
(5060 3005);
DISPLAY 0.489362 (5060 3005);
PAINT MONO (5060 3005);
FORCEPROP 1 LAST TOLERANCE 20%
J 0
(5100 3125);
DISPLAY 0.489362 (5100 3125);
PAINT SKYBLUE (5100 3125);
FORCEPROP 1 LAST VOLTAGE 16V
J 0
(5100 3175);
DISPLAY 0.489362 (5100 3175);
PAINT SKYBLUE (5100 3175);
FORCEPROP 1 LAST VALUE 22UF
J 0
(5100 3225);
DISPLAY 0.489362 (5100 3225);
PAINT SKYBLUE (5100 3225);
FORCEPROP 1 LAST PACK_TYPE C0805
J 0
(5100 3025);
DISPLAY 0.489362 (5100 3025);
PAINT SKYBLUE (5100 3025);
FORCEPROP 1 LAST MATERIAL X6S
J 0
(5100 3075);
DISPLAY 0.489362 (5100 3075);
PAINT SKYBLUE (5100 3075);
FORCEPROP 2 LAST CDS_LIB pure_quanta
J 0
(5050 3125);
DISPLAY INVISIBLE (5050 3125);
FORCEPROP 1 LAST PATH I42
J 0
(5100 3275);
DISPLAY 0.978723 (5100 3275);
PAINT WHITE (5100 3275);
DISPLAY INVISIBLE (5100 3275);
FORCEPROP 1 LAST PART_NUMBER CH6223MEA01
J 0
(5100 2975);
DISPLAY 0.489362 (5100 2975);
PAINT SKYBLUE (5100 2975);
DISPLAY INVISIBLE (5100 2975);
FORCEADD UNIVERSAL_GND..1
(4900 3925);
FORCEPROP 3 LASTPIN (4900 3975) SIG_NAME GND\g
J 0
(4910 3985);
DISPLAY 0.659574 (4910 3985);
PAINT MONO (4910 3985);
DISPLAY INVISIBLE (4910 3985);
FORCEPROP 2 LAST CDS_LIB pure_quanta_power
J 0
(4900 3925);
DISPLAY INVISIBLE (4900 3925);
FORCEPROP 1 LAST HDL_POWER GND
J 1
(4925 3850);
DISPLAY 0.872340 (4925 3850);
PAINT GREEN (4925 3850);
DISPLAY INVISIBLE (4925 3850);
FORCEPROP 1 LAST PATH I43
J 0
(4975 3925);
DISPLAY 0.872340 (4975 3925);
PAINT AQUA (4975 3925);
DISPLAY INVISIBLE (4975 3925);
FORCEADD Q_RES..2
(4900 4150);
FORCEPROP 1 LAST LOCATION PR158
J 0
(4945 4275);
DISPLAY 0.489362 (4945 4275);
PAINT SKYBLUE (4945 4275);
FORCEPROP 0 LAST $SEC 1
J 0
(4950 4325);
DISPLAY 0.680851 (4950 4325);
PAINT MONO (4950 4325);
DISPLAY INVISIBLE (4950 4325);
FORCEPROP 0 LAST CDS_SEC 1
J 0
(4950 4325);
DISPLAY 1.021277 (4950 4325);
DISPLAY INVISIBLE (4950 4325);
FORCEPROP 1 LASTPIN (4900 4250) $PN 1
J 0
(4905 4212);
DISPLAY 0.489362 (4905 4212);
PAINT MONO (4905 4212);
FORCEPROP 1 LASTPIN (4900 4050) $PN 2
J 0
(4905 4060);
DISPLAY 0.489362 (4905 4060);
PAINT MONO (4905 4060);
FORCEPROP 1 LAST PACK_TYPE 0402LF
J 0
(4940 3975);
DISPLAY 0.489362 (4940 3975);
PAINT SKYBLUE (4940 3975);
FORCEPROP 1 LAST VALUE 1.5
J 0
(4945 4225);
DISPLAY 0.489362 (4945 4225);
PAINT SKYBLUE (4945 4225);
FORCEPROP 1 LAST TOLERANCE 1%
J 0
(4945 4175);
DISPLAY 0.489362 (4945 4175);
PAINT SKYBLUE (4945 4175);
FORCEPROP 1 LAST MATERIAL EMPTY
J 0
(4940 4075);
DISPLAY 0.489362 (4940 4075);
PAINT RED (4940 4075);
FORCEPROP 1 LAST WATTAGE 1/8W
J 0
(4940 4125);
DISPLAY 0.489362 (4940 4125);
PAINT SKYBLUE (4940 4125);
FORCEPROP 2 LAST CDS_LIB pure_quanta
J 0
(4900 4150);
DISPLAY INVISIBLE (4900 4150);
FORCEPROP 1 LAST PATH I44
J 0
(4950 4325);
DISPLAY 0.978723 (4950 4325);
PAINT WHITE (4950 4325);
DISPLAY INVISIBLE (4950 4325);
FORCEPROP 1 LAST PART_NUMBER CS-1504FB00
J 0
(4940 4025);
DISPLAY 0.489362 (4940 4025);
PAINT SKYBLUE (4940 4025);
DISPLAY INVISIBLE (4940 4025);
FORCEADD Q_CAP..1
(5450 3125);
FORCEPROP 1 LAST LOCATION PC118_6
J 0
(5500 3275);
DISPLAY 0.489362 (5500 3275);
PAINT SKYBLUE (5500 3275);
FORCEPROP 0 LAST $SEC 1
J 0
(5500 3325);
DISPLAY 0.680851 (5500 3325);
PAINT MONO (5500 3325);
DISPLAY INVISIBLE (5500 3325);
FORCEPROP 0 LAST CDS_SEC 1
J 0
(5500 3325);
DISPLAY 1.021277 (5500 3325);
DISPLAY INVISIBLE (5500 3325);
FORCEPROP 1 LASTPIN (5450 3225) $PN 1
J 0
(5460 3205);
DISPLAY 0.489362 (5460 3205);
PAINT MONO (5460 3205);
FORCEPROP 1 LASTPIN (5450 3025) $PN 2
J 0
(5460 3005);
DISPLAY 0.489362 (5460 3005);
PAINT MONO (5460 3005);
FORCEPROP 1 LAST TOLERANCE 20%
J 0
(5500 3125);
DISPLAY 0.489362 (5500 3125);
PAINT SKYBLUE (5500 3125);
FORCEPROP 1 LAST VOLTAGE 16V
J 0
(5500 3175);
DISPLAY 0.489362 (5500 3175);
PAINT SKYBLUE (5500 3175);
FORCEPROP 1 LAST VALUE 22UF
J 0
(5500 3225);
DISPLAY 0.489362 (5500 3225);
PAINT SKYBLUE (5500 3225);
FORCEPROP 1 LAST MATERIAL X6S
J 0
(5500 3075);
DISPLAY 0.489362 (5500 3075);
PAINT SKYBLUE (5500 3075);
FORCEPROP 1 LAST PACK_TYPE C0805
J 0
(5500 3025);
DISPLAY 0.489362 (5500 3025);
PAINT SKYBLUE (5500 3025);
FORCEPROP 2 LAST CDS_LIB pure_quanta
J 0
(5450 3125);
DISPLAY INVISIBLE (5450 3125);
FORCEPROP 1 LAST PATH I45
J 0
(5500 3275);
DISPLAY 0.978723 (5500 3275);
PAINT WHITE (5500 3275);
DISPLAY INVISIBLE (5500 3275);
FORCEPROP 1 LAST PART_NUMBER CH6223MEA01
J 0
(5500 2975);
DISPLAY 0.489362 (5500 2975);
PAINT SKYBLUE (5500 2975);
DISPLAY INVISIBLE (5500 2975);
FORCEADD UNIVERSAL_GND..1
(5825 2775);
FORCEPROP 3 LASTPIN (5825 2825) SIG_NAME GND\g
J 0
(5835 2835);
DISPLAY 0.659574 (5835 2835);
PAINT MONO (5835 2835);
DISPLAY INVISIBLE (5835 2835);
FORCEPROP 2 LAST CDS_LIB pure_quanta_power
J 0
(5825 2775);
PAINT MONO (5825 2775);
DISPLAY INVISIBLE (5825 2775);
FORCEPROP 1 LAST HDL_POWER GND
J 1
(5850 2700);
DISPLAY 0.872340 (5850 2700);
PAINT GREEN (5850 2700);
DISPLAY INVISIBLE (5850 2700);
FORCEPROP 1 LAST PATH I46
J 0
(5900 2775);
DISPLAY 0.872340 (5900 2775);
PAINT AQUA (5900 2775);
DISPLAY INVISIBLE (5900 2775);
FORCEADD Q_CAP..1
(5825 3125);
FORCEPROP 1 LAST LOCATION PC119_6
J 0
(5875 3275);
DISPLAY 0.489362 (5875 3275);
PAINT SKYBLUE (5875 3275);
FORCEPROP 0 LAST $SEC 1
J 0
(5875 3325);
DISPLAY 0.680851 (5875 3325);
PAINT MONO (5875 3325);
DISPLAY INVISIBLE (5875 3325);
FORCEPROP 0 LAST CDS_SEC 1
J 0
(5875 3325);
DISPLAY 1.021277 (5875 3325);
DISPLAY INVISIBLE (5875 3325);
FORCEPROP 1 LASTPIN (5825 3225) $PN 1
J 0
(5835 3205);
DISPLAY 0.489362 (5835 3205);
PAINT MONO (5835 3205);
FORCEPROP 1 LASTPIN (5825 3025) $PN 2
J 0
(5835 3005);
DISPLAY 0.489362 (5835 3005);
PAINT MONO (5835 3005);
FORCEPROP 1 LAST TOLERANCE 20%
J 0
(5875 3125);
DISPLAY 0.489362 (5875 3125);
PAINT SKYBLUE (5875 3125);
FORCEPROP 1 LAST VOLTAGE 16V
J 0
(5875 3175);
DISPLAY 0.489362 (5875 3175);
PAINT SKYBLUE (5875 3175);
FORCEPROP 1 LAST VALUE 22UF
J 0
(5875 3225);
DISPLAY 0.489362 (5875 3225);
PAINT SKYBLUE (5875 3225);
FORCEPROP 1 LAST MATERIAL X6S
J 0
(5875 3075);
DISPLAY 0.489362 (5875 3075);
PAINT SKYBLUE (5875 3075);
FORCEPROP 1 LAST PACK_TYPE C0805
J 0
(5875 3025);
DISPLAY 0.489362 (5875 3025);
PAINT SKYBLUE (5875 3025);
FORCEPROP 2 LAST CDS_LIB pure_quanta
J 0
(5825 3125);
DISPLAY INVISIBLE (5825 3125);
FORCEPROP 1 LAST PATH I47
J 0
(5875 3275);
DISPLAY 0.978723 (5875 3275);
PAINT WHITE (5875 3275);
DISPLAY INVISIBLE (5875 3275);
FORCEPROP 1 LAST PART_NUMBER CH6223MEA01
J 0
(5875 2975);
DISPLAY 0.489362 (5875 2975);
PAINT SKYBLUE (5875 2975);
DISPLAY INVISIBLE (5875 2975);
FORCEADD VCC_CORE..1
(5825 3475);
FORCEPROP 3 LASTPIN (5825 3425) SIG_NAME SW_P12V_AUX_PVDDCR_CPU1_P0_FLT\g
J 0
(5835 3435);
DISPLAY 0.659574 (5835 3435);
PAINT MONO (5835 3435);
DISPLAY INVISIBLE (5835 3435);
FORCEPROP 1 LAST HDL_POWER SW_P12V_AUX_PVDDCR_CPU1_P0_FLT
J 1
(5825 3525);
DISPLAY 0.489362 (5825 3525);
PAINT GREEN (5825 3525);
FORCEPROP 2 LAST CDS_LIB pure_quanta_power
J 0
(5825 3475);
DISPLAY INVISIBLE (5825 3475);
FORCEPROP 1 LAST PATH I48
J 0
(5875 3500);
DISPLAY 0.872340 (5875 3500);
PAINT AQUA (5875 3500);
DISPLAY INVISIBLE (5875 3500);
FORCEADD Q_RES..1
(6050 3800);
FORCEPROP 1 LAST LOCATION PR96
J 0
(6025 3825);
DISPLAY 0.489362 (6025 3825);
PAINT SKYBLUE (6025 3825);
FORCEPROP 0 LAST $SEC 1
J 0
(6300 3950);
DISPLAY 0.680851 (6300 3950);
PAINT MONO (6300 3950);
DISPLAY INVISIBLE (6300 3950);
FORCEPROP 0 LAST CDS_SEC 1
J 0
(6300 3950);
DISPLAY 1.021277 (6300 3950);
DISPLAY INVISIBLE (6300 3950);
FORCEPROP 1 LASTPIN (5950 3800) $PN 1
J 0
(5962 3812);
DISPLAY 0.489362 (5962 3812);
PAINT MONO (5962 3812);
FORCEPROP 1 LASTPIN (6150 3800) $PN 2
J 0
(6112 3812);
DISPLAY 0.489362 (6112 3812);
PAINT MONO (6112 3812);
FORCEPROP 1 LAST TOLERANCE 5%
J 0
(5900 3825);
DISPLAY 0.489362 (5900 3825);
PAINT SKYBLUE (5900 3825);
FORCEPROP 1 LAST VALUE 0
J 2
(5825 3825);
DISPLAY 0.489362 (5825 3825);
PAINT SKYBLUE (5825 3825);
FORCEPROP 1 LAST PACK_TYPE 0402LF
J 0
(6125 3750);
DISPLAY 0.489362 (6125 3750);
PAINT SKYBLUE (6125 3750);
FORCEPROP 1 LAST WATTAGE 1/16W
J 2
(6300 3825);
DISPLAY 0.489362 (6300 3825);
PAINT SKYBLUE (6300 3825);
FORCEPROP 1 LAST MATERIAL CHIP
J 0
(6150 3700);
DISPLAY 0.489362 (6150 3700);
PAINT SKYBLUE (6150 3700);
FORCEPROP 2 LAST CDS_LIB pure_quanta
J 0
(6050 3800);
DISPLAY INVISIBLE (6050 3800);
FORCEPROP 1 LAST PATH I49
J 0
(6000 3950);
DISPLAY 0.978723 (6000 3950);
PAINT WHITE (6000 3950);
DISPLAY INVISIBLE (6000 3950);
FORCEPROP 1 LAST PART_NUMBER CS00002JB13
J 0
(5750 3750);
DISPLAY 0.489362 (5750 3750);
PAINT SKYBLUE (5750 3750);
DISPLAY INVISIBLE (5750 3750);
FORCEADD OFFPAGE..1
(1925 1625);
FORCEPROP 2 LAST $XR0 200 
J 0
(1643 1625);
DISPLAY 0.638298 (1643 1625);
PAINT MONO (1643 1625);
FORCEPROP 2 LAST CDS_LIB standard
J 0
(1925 1625);
DISPLAY INVISIBLE (1925 1625);
FORCEPROP 1 LAST OFFPAGE TRUE
J 0
(2250 1500);
DISPLAY 0.872340 (2250 1500);
PAINT GREEN (2250 1500);
DISPLAY INVISIBLE (2250 1500);
FORCEPROP 1 LAST COMMENT_BODY TRUE
J 0
(2050 1525);
DISPLAY 0.872340 (2050 1525);
PAINT GREEN (2050 1525);
DISPLAY INVISIBLE (2050 1525);
FORCEPROP 2 LAST PATH I5
J 0
(1675 1675);
DISPLAY 0.680851 (1675 1675);
DISPLAY INVISIBLE (1675 1675);
FORCEADD OFFPAGE..3
(7150 1975);
FORCEPROP 2 LAST $XR0 203 
J 0
(7394 1975);
DISPLAY 0.638298 (7394 1975);
PAINT MONO (7394 1975);
FORCEPROP 2 LAST CDS_LIB standard
J 0
(7150 1975);
DISPLAY INVISIBLE (7150 1975);
FORCEPROP 1 LAST OFFPAGE TRUE
J 0
(7475 1850);
DISPLAY 0.872340 (7475 1850);
PAINT GREEN (7475 1850);
DISPLAY INVISIBLE (7475 1850);
FORCEPROP 1 LAST COMMENT_BODY TRUE
J 0
(7100 1875);
DISPLAY 0.872340 (7100 1875);
PAINT GREEN (7100 1875);
DISPLAY INVISIBLE (7100 1875);
FORCEPROP 2 LAST PATH I50
J 0
(7400 2025);
DISPLAY 0.680851 (7400 2025);
DISPLAY INVISIBLE (7400 2025);
FORCEADD Q_CAP..1
(7675 2025);
FORCEPROP 1 LAST LOCATION PC120_6
J 0
(7725 2150);
DISPLAY 0.489362 (7725 2150);
PAINT SKYBLUE (7725 2150);
FORCEPROP 0 LAST $SEC 1
J 0
(7725 2200);
DISPLAY 0.680851 (7725 2200);
PAINT MONO (7725 2200);
DISPLAY INVISIBLE (7725 2200);
FORCEPROP 0 LAST CDS_SEC 1
J 0
(7725 2200);
DISPLAY 1.021277 (7725 2200);
DISPLAY INVISIBLE (7725 2200);
FORCEPROP 1 LASTPIN (7675 2125) $PN 1
J 0
(7685 2105);
DISPLAY 0.489362 (7685 2105);
PAINT MONO (7685 2105);
FORCEPROP 1 LASTPIN (7675 1925) $PN 2
J 0
(7685 1905);
DISPLAY 0.489362 (7685 1905);
PAINT MONO (7685 1905);
FORCEPROP 1 LAST PACK_TYPE C0805
J 0
(7725 1900);
DISPLAY 0.489362 (7725 1900);
PAINT SKYBLUE (7725 1900);
FORCEPROP 1 LAST MATERIAL X6S
J 0
(7725 1950);
DISPLAY 0.489362 (7725 1950);
PAINT SKYBLUE (7725 1950);
FORCEPROP 1 LAST TOLERANCE 20%
J 0
(7725 2000);
DISPLAY 0.489362 (7725 2000);
PAINT SKYBLUE (7725 2000);
FORCEPROP 1 LAST VALUE 22UF
J 0
(7725 2100);
DISPLAY 0.489362 (7725 2100);
PAINT SKYBLUE (7725 2100);
FORCEPROP 1 LAST VOLTAGE 4V
J 0
(7725 2050);
DISPLAY 0.489362 (7725 2050);
PAINT SKYBLUE (7725 2050);
FORCEPROP 2 LAST CDS_LIB pure_quanta
J 0
(7675 2025);
DISPLAY INVISIBLE (7675 2025);
FORCEPROP 1 LAST PATH I51
J 0
(7725 2175);
DISPLAY 0.978723 (7725 2175);
PAINT WHITE (7725 2175);
DISPLAY INVISIBLE (7725 2175);
FORCEPROP 1 LAST PART_NUMBER CH622KMEA03
J 0
(7725 1850);
DISPLAY 0.489362 (7725 1850);
PAINT SKYBLUE (7725 1850);
DISPLAY INVISIBLE (7725 1850);
FORCEADD UNIVERSAL_GND..1
(8100 1675);
FORCEPROP 3 LASTPIN (8100 1725) SIG_NAME GND\g
J 0
(8110 1735);
DISPLAY 0.659574 (8110 1735);
PAINT MONO (8110 1735);
DISPLAY INVISIBLE (8110 1735);
FORCEPROP 2 LAST CDS_LIB pure_quanta_power
J 0
(8100 1675);
PAINT MONO (8100 1675);
DISPLAY INVISIBLE (8100 1675);
FORCEPROP 1 LAST HDL_POWER GND
J 1
(8125 1600);
DISPLAY 0.872340 (8125 1600);
PAINT GREEN (8125 1600);
DISPLAY INVISIBLE (8125 1600);
FORCEPROP 1 LAST PATH I52
J 0
(8175 1675);
DISPLAY 0.872340 (8175 1675);
PAINT AQUA (8175 1675);
DISPLAY INVISIBLE (8175 1675);
FORCEADD Q_CAP..1
(8100 2025);
FORCEPROP 1 LAST LOCATION PC123_6
J 0
(8150 2150);
DISPLAY 0.489362 (8150 2150);
PAINT SKYBLUE (8150 2150);
FORCEPROP 0 LAST $SEC 1
J 0
(8150 2200);
DISPLAY 0.680851 (8150 2200);
PAINT MONO (8150 2200);
DISPLAY INVISIBLE (8150 2200);
FORCEPROP 0 LAST CDS_SEC 1
J 0
(8150 2200);
DISPLAY 1.021277 (8150 2200);
DISPLAY INVISIBLE (8150 2200);
FORCEPROP 1 LASTPIN (8100 2125) $PN 1
J 0
(8110 2105);
DISPLAY 0.489362 (8110 2105);
PAINT MONO (8110 2105);
FORCEPROP 1 LASTPIN (8100 1925) $PN 2
J 0
(8110 1905);
DISPLAY 0.489362 (8110 1905);
PAINT MONO (8110 1905);
FORCEPROP 1 LAST PACK_TYPE C0805
J 0
(8150 1900);
DISPLAY 0.489362 (8150 1900);
PAINT SKYBLUE (8150 1900);
FORCEPROP 1 LAST MATERIAL X6S
J 0
(8150 1950);
DISPLAY 0.489362 (8150 1950);
PAINT SKYBLUE (8150 1950);
FORCEPROP 1 LAST TOLERANCE 20%
J 0
(8150 2000);
DISPLAY 0.489362 (8150 2000);
PAINT SKYBLUE (8150 2000);
FORCEPROP 1 LAST VALUE 22UF
J 0
(8150 2100);
DISPLAY 0.489362 (8150 2100);
PAINT SKYBLUE (8150 2100);
FORCEPROP 1 LAST VOLTAGE 4V
J 0
(8150 2050);
DISPLAY 0.489362 (8150 2050);
PAINT SKYBLUE (8150 2050);
FORCEPROP 2 LAST CDS_LIB pure_quanta
J 0
(8100 2025);
DISPLAY INVISIBLE (8100 2025);
FORCEPROP 1 LAST PATH I53
J 0
(8150 2175);
DISPLAY 0.978723 (8150 2175);
PAINT WHITE (8150 2175);
DISPLAY INVISIBLE (8150 2175);
FORCEPROP 1 LAST PART_NUMBER CH622KMEA03
J 0
(8150 1850);
DISPLAY 0.489362 (8150 1850);
PAINT SKYBLUE (8150 1850);
DISPLAY INVISIBLE (8150 1850);
FORCEADD VCC_CORE..1
(8100 2375);
FORCEPROP 3 LASTPIN (8100 2325) SIG_NAME PVDDCR_CPU1_P0\g
J 0
(8110 2335);
DISPLAY 0.659574 (8110 2335);
PAINT MONO (8110 2335);
DISPLAY INVISIBLE (8110 2335);
FORCEPROP 1 LAST HDL_POWER PVDDCR_CPU1_P0
J 1
(8100 2425);
DISPLAY 0.489362 (8100 2425);
PAINT GREEN (8100 2425);
FORCEPROP 2 LAST CDS_LIB pure_quanta_power
J 0
(8100 2375);
DISPLAY INVISIBLE (8100 2375);
FORCEPROP 1 LAST PATH I54
J 0
(8150 2400);
DISPLAY 0.872340 (8150 2400);
PAINT AQUA (8150 2400);
DISPLAY INVISIBLE (8150 2400);
FORCEADD UNIVERSAL_GND..1
(8125 4325);
FORCEPROP 3 LASTPIN (8125 4375) SIG_NAME GND\g
J 0
(8135 4385);
DISPLAY 0.659574 (8135 4385);
PAINT MONO (8135 4385);
DISPLAY INVISIBLE (8135 4385);
FORCEPROP 2 LAST CDS_LIB pure_quanta_power
J 0
(8125 4325);
PAINT MONO (8125 4325);
DISPLAY INVISIBLE (8125 4325);
FORCEPROP 1 LAST HDL_POWER GND
J 1
(8150 4250);
DISPLAY 0.872340 (8150 4250);
PAINT GREEN (8150 4250);
DISPLAY INVISIBLE (8150 4250);
FORCEPROP 1 LAST PATH I55
J 0
(8200 4325);
DISPLAY 0.872340 (8200 4325);
PAINT AQUA (8200 4325);
DISPLAY INVISIBLE (8200 4325);
FORCEADD Q_RES..1
(4650 5225);
FORCEPROP 1 LAST LOCATION PR95
J 0
(4425 5300);
DISPLAY 0.489362 (4425 5300);
PAINT SKYBLUE (4425 5300);
FORCEPROP 0 LAST $SEC 1
J 0
(4925 5325);
DISPLAY 0.680851 (4925 5325);
PAINT MONO (4925 5325);
DISPLAY INVISIBLE (4925 5325);
FORCEPROP 0 LAST CDS_SEC 1
J 0
(4925 5325);
DISPLAY 1.021277 (4925 5325);
DISPLAY INVISIBLE (4925 5325);
FORCEPROP 1 LASTPIN (4550 5225) $PN 1
J 0
(4562 5237);
DISPLAY 0.787234 (4562 5237);
PAINT MONO (4562 5237);
DISPLAY INVISIBLE (4562 5237);
FORCEPROP 1 LASTPIN (4750 5225) $PN 2
J 0
(4712 5237);
DISPLAY 0.787234 (4712 5237);
PAINT MONO (4712 5237);
DISPLAY INVISIBLE (4712 5237);
FORCEPROP 1 LAST VALUE 5.6
J 2
(4600 5300);
DISPLAY 0.489362 (4600 5300);
PAINT SKYBLUE (4600 5300);
FORCEPROP 1 LAST WATTAGE 1/16W
J 2
(4925 5300);
DISPLAY 0.489362 (4925 5300);
PAINT SKYBLUE (4925 5300);
FORCEPROP 1 LAST PACK_TYPE 0402LF
J 0
(5050 5150);
DISPLAY 0.489362 (5050 5150);
PAINT SKYBLUE (5050 5150);
FORCEPROP 1 LAST TOLERANCE 1%
J 0
(4650 5300);
DISPLAY 0.489362 (4650 5300);
PAINT SKYBLUE (4650 5300);
FORCEPROP 1 LAST MATERIAL CHIP
J 0
(4500 5150);
DISPLAY 0.489362 (4500 5150);
PAINT SKYBLUE (4500 5150);
FORCEPROP 2 LAST CDS_LIB pure_quanta
J 0
(4650 5225);
DISPLAY INVISIBLE (4650 5225);
FORCEPROP 1 LAST PATH I56
J 0
(4600 5375);
DISPLAY 0.978723 (4600 5375);
PAINT WHITE (4600 5375);
DISPLAY INVISIBLE (4600 5375);
FORCEPROP 1 LAST PART_NUMBER CS-5602FB01
J 0
(4675 5150);
DISPLAY 0.489362 (4675 5150);
PAINT SKYBLUE (4675 5150);
DISPLAY INVISIBLE (4675 5150);
FORCEADD Q_CAP..1
(4900 4675);
FORCEPROP 1 LAST LOCATION PC157
J 0
(4950 4775);
DISPLAY 0.489362 (4950 4775);
PAINT SKYBLUE (4950 4775);
FORCEPROP 0 LAST $SEC 1
J 0
(4950 4825);
DISPLAY 0.680851 (4950 4825);
PAINT MONO (4950 4825);
DISPLAY INVISIBLE (4950 4825);
FORCEPROP 0 LAST CDS_SEC 1
J 0
(4950 4825);
DISPLAY 1.021277 (4950 4825);
DISPLAY INVISIBLE (4950 4825);
FORCEPROP 1 LASTPIN (4900 4775) $PN 1
J 0
(4910 4755);
DISPLAY 0.489362 (4910 4755);
PAINT MONO (4910 4755);
FORCEPROP 1 LASTPIN (4900 4575) $PN 2
J 0
(4910 4555);
DISPLAY 0.489362 (4910 4555);
PAINT MONO (4910 4555);
FORCEPROP 1 LAST PACK_TYPE C0402
J 0
(4950 4475);
DISPLAY 0.489362 (4950 4475);
PAINT SKYBLUE (4950 4475);
FORCEPROP 1 LAST VOLTAGE 50V
J 0
(4950 4675);
DISPLAY 0.489362 (4950 4675);
PAINT SKYBLUE (4950 4675);
FORCEPROP 1 LAST VALUE 560PF
J 0
(4950 4725);
DISPLAY 0.489362 (4950 4725);
PAINT SKYBLUE (4950 4725);
FORCEPROP 1 LAST TOLERANCE 10%
J 0
(4950 4625);
DISPLAY 0.489362 (4950 4625);
PAINT SKYBLUE (4950 4625);
FORCEPROP 1 LAST MATERIAL EMPTY
J 0
(4950 4575);
DISPLAY 0.489362 (4950 4575);
PAINT RED (4950 4575);
FORCEPROP 2 LAST CDS_LIB pure_quanta
J 0
(4900 4675);
DISPLAY INVISIBLE (4900 4675);
FORCEPROP 1 LAST PATH I57
J 0
(4950 4825);
DISPLAY 0.978723 (4950 4825);
PAINT WHITE (4950 4825);
DISPLAY INVISIBLE (4950 4825);
FORCEPROP 1 LAST PART_NUMBER CH1566K1B09
J 0
(4950 4525);
DISPLAY 0.489362 (4950 4525);
PAINT SKYBLUE (4950 4525);
DISPLAY INVISIBLE (4950 4525);
FORCEADD Q_CAP..1
(4250 5775);
FORCEPROP 1 LAST LOCATION PC134_5
J 0
(4300 5925);
DISPLAY 0.489362 (4300 5925);
PAINT SKYBLUE (4300 5925);
FORCEPROP 0 LAST $SEC 1
J 0
(4300 5925);
DISPLAY 0.680851 (4300 5925);
PAINT MONO (4300 5925);
DISPLAY INVISIBLE (4300 5925);
FORCEPROP 0 LAST CDS_SEC 1
J 0
(4300 5925);
DISPLAY 1.021277 (4300 5925);
DISPLAY INVISIBLE (4300 5925);
FORCEPROP 1 LASTPIN (4250 5875) $PN 1
J 0
(4260 5855);
DISPLAY 0.489362 (4260 5855);
PAINT MONO (4260 5855);
FORCEPROP 1 LASTPIN (4250 5675) $PN 2
J 0
(4260 5655);
DISPLAY 0.489362 (4260 5655);
PAINT MONO (4260 5655);
FORCEPROP 1 LAST PACK_TYPE 0402
J 0
(4300 5625);
DISPLAY 0.489362 (4300 5625);
PAINT SKYBLUE (4300 5625);
FORCEPROP 1 LAST VOLTAGE 25V
J 0
(4300 5825);
DISPLAY 0.489362 (4300 5825);
PAINT SKYBLUE (4300 5825);
FORCEPROP 1 LAST VALUE 0.1UF
J 0
(4300 5875);
DISPLAY 0.489362 (4300 5875);
PAINT SKYBLUE (4300 5875);
FORCEPROP 1 LAST TOLERANCE 10%
J 0
(4300 5775);
DISPLAY 0.489362 (4300 5775);
PAINT SKYBLUE (4300 5775);
FORCEPROP 1 LAST MATERIAL X7R
J 0
(4300 5725);
DISPLAY 0.489362 (4300 5725);
PAINT SKYBLUE (4300 5725);
FORCEPROP 2 LAST CDS_LIB pure_quanta
J 0
(4250 5775);
DISPLAY INVISIBLE (4250 5775);
FORCEPROP 1 LAST PATH I58
J 0
(4300 5925);
DISPLAY 0.978723 (4300 5925);
PAINT WHITE (4300 5925);
DISPLAY INVISIBLE (4300 5925);
FORCEPROP 1 LAST PART_NUMBER CH4104K1B00
J 0
(4300 5675);
DISPLAY 0.489362 (4300 5675);
PAINT SKYBLUE (4300 5675);
DISPLAY INVISIBLE (4300 5675);
FORCEADD Q_CAP..1
(4675 5775);
FORCEPROP 1 LAST LOCATION PC135_5
J 0
(4725 5925);
DISPLAY 0.489362 (4725 5925);
PAINT SKYBLUE (4725 5925);
FORCEPROP 0 LAST $SEC 1
J 0
(4725 5975);
DISPLAY 0.680851 (4725 5975);
PAINT MONO (4725 5975);
DISPLAY INVISIBLE (4725 5975);
FORCEPROP 0 LAST CDS_SEC 1
J 0
(4725 5975);
DISPLAY 1.021277 (4725 5975);
DISPLAY INVISIBLE (4725 5975);
FORCEPROP 1 LASTPIN (4675 5875) $PN 1
J 0
(4685 5855);
DISPLAY 0.489362 (4685 5855);
PAINT MONO (4685 5855);
FORCEPROP 1 LASTPIN (4675 5675) $PN 2
J 0
(4685 5655);
DISPLAY 0.489362 (4685 5655);
PAINT MONO (4685 5655);
FORCEPROP 1 LAST PACK_TYPE C0402
J 0
(4725 5675);
DISPLAY 0.489362 (4725 5675);
PAINT SKYBLUE (4725 5675);
FORCEPROP 1 LAST VOLTAGE 25V
J 0
(4725 5825);
DISPLAY 0.489362 (4725 5825);
PAINT SKYBLUE (4725 5825);
FORCEPROP 1 LAST VALUE 1UF
J 0
(4725 5875);
DISPLAY 0.489362 (4725 5875);
PAINT SKYBLUE (4725 5875);
FORCEPROP 1 LAST TOLERANCE 10%
J 0
(4725 5775);
DISPLAY 0.489362 (4725 5775);
PAINT SKYBLUE (4725 5775);
FORCEPROP 1 LAST MATERIAL X6S
J 0
(4725 5725);
DISPLAY 0.489362 (4725 5725);
PAINT SKYBLUE (4725 5725);
FORCEPROP 2 LAST CDS_LIB pure_quanta
J 0
(4675 5775);
DISPLAY INVISIBLE (4675 5775);
FORCEPROP 1 LAST PATH I59
J 0
(4725 5925);
DISPLAY 0.978723 (4725 5925);
PAINT WHITE (4725 5925);
DISPLAY INVISIBLE (4725 5925);
FORCEPROP 1 LAST PART_NUMBER CH5104KEB02
J 0
(4725 5625);
DISPLAY 0.489362 (4725 5625);
PAINT SKYBLUE (4725 5625);
DISPLAY INVISIBLE (4725 5625);
FORCEADD OFFPAGE..5
(1925 1725);
FORCEPROP 2 LAST $XR3 200 
J 0
(1670 1797);
DISPLAY 0.638298 (1670 1797);
PAINT MONO (1670 1797);
FORCEPROP 2 LAST $XR2 203 
J 0
(1670 1761);
DISPLAY 0.638298 (1670 1761);
PAINT MONO (1670 1761);
FORCEPROP 2 LAST $XR1 202 
J 0
(1670 1689);
DISPLAY 0.638298 (1670 1689);
PAINT MONO (1670 1689);
FORCEPROP 2 LAST $XR0 201 
J 0
(1670 1725);
DISPLAY 0.638298 (1670 1725);
PAINT MONO (1670 1725);
FORCEPROP 2 LAST CDS_LIB standard
J 0
(1925 1725);
DISPLAY INVISIBLE (1925 1725);
FORCEPROP 1 LAST OFFPAGE TRUE
J 0
(2250 1600);
DISPLAY 0.872340 (2250 1600);
PAINT GREEN (2250 1600);
DISPLAY INVISIBLE (2250 1600);
FORCEPROP 1 LAST COMMENT_BODY TRUE
J 0
(2025 1650);
DISPLAY 0.872340 (2025 1650);
PAINT GREEN (2025 1650);
DISPLAY INVISIBLE (2025 1650);
FORCEPROP 2 LAST PATH I6
J 0
(1650 1850);
DISPLAY 0.680851 (1650 1850);
DISPLAY INVISIBLE (1650 1850);
FORCEADD Q_CAP..1
(5075 5775);
FORCEPROP 1 LAST LOCATION PC136_5
J 0
(5125 5925);
DISPLAY 0.489362 (5125 5925);
PAINT SKYBLUE (5125 5925);
FORCEPROP 0 LAST $SEC 1
J 0
(5125 5975);
DISPLAY 0.680851 (5125 5975);
PAINT MONO (5125 5975);
DISPLAY INVISIBLE (5125 5975);
FORCEPROP 0 LAST CDS_SEC 1
J 0
(5125 5975);
DISPLAY 1.021277 (5125 5975);
DISPLAY INVISIBLE (5125 5975);
FORCEPROP 1 LASTPIN (5075 5875) $PN 1
J 0
(5085 5855);
DISPLAY 0.489362 (5085 5855);
PAINT MONO (5085 5855);
FORCEPROP 1 LASTPIN (5075 5675) $PN 2
J 0
(5085 5655);
DISPLAY 0.489362 (5085 5655);
PAINT MONO (5085 5655);
FORCEPROP 1 LAST TOLERANCE 20%
J 0
(5125 5775);
DISPLAY 0.489362 (5125 5775);
PAINT SKYBLUE (5125 5775);
FORCEPROP 1 LAST VOLTAGE 16V
J 0
(5125 5825);
DISPLAY 0.489362 (5125 5825);
PAINT SKYBLUE (5125 5825);
FORCEPROP 1 LAST VALUE 22UF
J 0
(5125 5875);
DISPLAY 0.489362 (5125 5875);
PAINT SKYBLUE (5125 5875);
FORCEPROP 1 LAST MATERIAL X6S
J 0
(5125 5725);
DISPLAY 0.489362 (5125 5725);
PAINT SKYBLUE (5125 5725);
FORCEPROP 1 LAST PACK_TYPE C0805
J 0
(5125 5675);
DISPLAY 0.489362 (5125 5675);
PAINT SKYBLUE (5125 5675);
FORCEPROP 2 LAST CDS_LIB pure_quanta
J 0
(5075 5775);
DISPLAY INVISIBLE (5075 5775);
FORCEPROP 1 LAST PATH I60
J 0
(5125 5925);
DISPLAY 0.978723 (5125 5925);
PAINT WHITE (5125 5925);
DISPLAY INVISIBLE (5125 5925);
FORCEPROP 1 LAST PART_NUMBER CH6223MEA01
J 0
(5125 5625);
DISPLAY 0.489362 (5125 5625);
PAINT SKYBLUE (5125 5625);
DISPLAY INVISIBLE (5125 5625);
FORCEADD OFFPAGE..6
(5375 4625);
FORCEPROP 2 LAST $XR0 203 
J 0
(5095 4625);
DISPLAY 0.638298 (5095 4625);
PAINT MONO (5095 4625);
FORCEPROP 2 LAST CDS_LIB standard
J 0
(5375 4625);
DISPLAY INVISIBLE (5375 4625);
FORCEPROP 1 LAST OFFPAGE TRUE
J 0
(5700 4500);
DISPLAY 0.872340 (5700 4500);
PAINT GREEN (5700 4500);
DISPLAY INVISIBLE (5700 4500);
FORCEPROP 1 LAST COMMENT_BODY TRUE
J 0
(5475 4550);
DISPLAY 0.872340 (5475 4550);
PAINT GREEN (5475 4550);
DISPLAY INVISIBLE (5475 4550);
FORCEPROP 2 LAST PATH I61
J 0
(5100 4675);
DISPLAY 0.680851 (5100 4675);
DISPLAY INVISIBLE (5100 4675);
FORCEADD Q_CAP..1
(5375 5100);
FORCEPROP 1 LAST LOCATION PC137
J 0
(5425 5200);
DISPLAY 0.489362 (5425 5200);
PAINT SKYBLUE (5425 5200);
FORCEPROP 0 LAST $SEC 1
J 0
(5425 5250);
DISPLAY 0.680851 (5425 5250);
PAINT MONO (5425 5250);
DISPLAY INVISIBLE (5425 5250);
FORCEPROP 0 LAST CDS_SEC 1
J 2
(5425 5225);
DISPLAY 1.021277 (5425 5225);
DISPLAY INVISIBLE (5425 5225);
FORCEPROP 1 LASTPIN (5375 5200) $PN 1
J 0
(5385 5180);
DISPLAY 0.489362 (5385 5180);
PAINT MONO (5385 5180);
FORCEPROP 1 LASTPIN (5375 5000) $PN 2
J 0
(5385 4980);
DISPLAY 0.489362 (5385 4980);
PAINT MONO (5385 4980);
FORCEPROP 1 LAST VOLTAGE 16V
J 0
(5425 5100);
DISPLAY 0.489362 (5425 5100);
PAINT SKYBLUE (5425 5100);
FORCEPROP 1 LAST VALUE 0.22UF
J 0
(5425 5150);
DISPLAY 0.489362 (5425 5150);
PAINT SKYBLUE (5425 5150);
FORCEPROP 1 LAST PACK_TYPE 0402
J 0
(5425 4900);
DISPLAY 0.489362 (5425 4900);
PAINT SKYBLUE (5425 4900);
FORCEPROP 1 LAST MATERIAL X7R
J 0
(5425 5000);
DISPLAY 0.489362 (5425 5000);
PAINT SKYBLUE (5425 5000);
FORCEPROP 1 LAST TOLERANCE 10%
J 0
(5425 5050);
DISPLAY 0.489362 (5425 5050);
PAINT SKYBLUE (5425 5050);
FORCEPROP 2 LAST CDS_LIB pure_quanta
J 2
(5375 5100);
DISPLAY INVISIBLE (5375 5100);
FORCEPROP 1 LAST PATH I62
J 0
(5425 5250);
DISPLAY 0.978723 (5425 5250);
PAINT WHITE (5425 5250);
DISPLAY INVISIBLE (5425 5250);
FORCEPROP 1 LAST PART_NUMBER CH4223K1B00
J 0
(5425 4950);
DISPLAY 0.489362 (5425 4950);
PAINT SKYBLUE (5425 4950);
DISPLAY INVISIBLE (5425 4950);
FORCEADD Q_INDUCTOR4P_14..1
(6300 4750);
FORCEPROP 1 LAST LOCATION PL15
J 0
(6100 5000);
DISPLAY 0.489362 (6100 5000);
PAINT SKYBLUE (6100 5000);
FORCEPROP 0 LAST $SEC 1
J 0
(6075 5050);
DISPLAY 0.680851 (6075 5050);
PAINT MONO (6075 5050);
DISPLAY INVISIBLE (6075 5050);
FORCEPROP 0 LAST CDS_SEC 1
J 0
(6075 5050);
DISPLAY 1.021277 (6075 5050);
DISPLAY INVISIBLE (6075 5050);
FORCEPROP 0 LASTPIN (5900 4875) $PN 1
J 2
(5890 4885);
DISPLAY 0.489362 (5890 4885);
PAINT MONO (5890 4885);
FORCEPROP 0 LASTPIN (5900 4625) $PN 2
J 2
(5890 4635);
DISPLAY 0.489362 (5890 4635);
PAINT MONO (5890 4635);
FORCEPROP 0 LASTPIN (6700 4625) $PN 3
J 0
(6710 4635);
DISPLAY 0.489362 (6710 4635);
PAINT MONO (6710 4635);
FORCEPROP 0 LASTPIN (6700 4875) $PN 4
J 0
(6710 4885);
DISPLAY 0.489362 (6710 4885);
PAINT MONO (6710 4885);
FORCEPROP 2 LAST PART_TYPE SMLF
J 0
(6225 4500);
DISPLAY 1.021277 (6225 4500);
FORCEPROP 2 LAST VALUE 150NH
J 0
(6200 4925);
DISPLAY 0.489362 (6200 4925);
PAINT SKYBLUE (6200 4925);
FORCEPROP 1 LAST MATERIAL IND
J 0
(6100 4925);
DISPLAY 0.489362 (6100 4925);
PAINT SKYBLUE (6100 4925);
FORCEPROP 1 LAST NEEDS_NO_SIZE TRUE
J 0
(6300 4750);
DISPLAY 0.468085 (6300 4750);
PAINT GREEN (6300 4750);
DISPLAY INVISIBLE (6300 4750);
FORCEPROP 2 LAST CDS_LIB pure_quanta
J 0
(6300 4750);
DISPLAY INVISIBLE (6300 4750);
FORCEPROP 1 LAST PATH I63
J 0
(6500 4905);
DISPLAY 0.723404 (6500 4905);
PAINT GREEN (6500 4905);
DISPLAY INVISIBLE (6500 4905);
FORCEPROP 1 LAST PART_NUMBER CV+15^0TZ04
J 0
(6350 4925);
DISPLAY 0.489362 (6350 4925);
PAINT SKYBLUE (6350 4925);
DISPLAY INVISIBLE (6350 4925);
FORCEADD UNIVERSAL_GND..1
(5850 5425);
FORCEPROP 3 LASTPIN (5850 5475) SIG_NAME GND\g
J 0
(5860 5485);
DISPLAY 0.659574 (5860 5485);
PAINT MONO (5860 5485);
DISPLAY INVISIBLE (5860 5485);
FORCEPROP 2 LAST CDS_LIB pure_quanta_power
J 0
(5850 5425);
PAINT MONO (5850 5425);
DISPLAY INVISIBLE (5850 5425);
FORCEPROP 1 LAST HDL_POWER GND
J 1
(5875 5350);
DISPLAY 0.872340 (5875 5350);
PAINT GREEN (5875 5350);
DISPLAY INVISIBLE (5875 5350);
FORCEPROP 1 LAST PATH I64
J 0
(5925 5425);
DISPLAY 0.872340 (5925 5425);
PAINT AQUA (5925 5425);
DISPLAY INVISIBLE (5925 5425);
FORCEADD Q_CAP..1
(5475 5775);
FORCEPROP 1 LAST LOCATION PC138_5
J 0
(5525 5925);
DISPLAY 0.489362 (5525 5925);
PAINT SKYBLUE (5525 5925);
FORCEPROP 0 LAST $SEC 1
J 0
(5525 5975);
DISPLAY 0.680851 (5525 5975);
PAINT MONO (5525 5975);
DISPLAY INVISIBLE (5525 5975);
FORCEPROP 0 LAST CDS_SEC 1
J 0
(5525 5975);
DISPLAY 1.021277 (5525 5975);
DISPLAY INVISIBLE (5525 5975);
FORCEPROP 1 LASTPIN (5475 5875) $PN 1
J 0
(5485 5855);
DISPLAY 0.489362 (5485 5855);
PAINT MONO (5485 5855);
FORCEPROP 1 LASTPIN (5475 5675) $PN 2
J 0
(5485 5655);
DISPLAY 0.489362 (5485 5655);
PAINT MONO (5485 5655);
FORCEPROP 1 LAST PACK_TYPE C0805
J 0
(5525 5675);
DISPLAY 0.489362 (5525 5675);
PAINT SKYBLUE (5525 5675);
FORCEPROP 1 LAST VOLTAGE 16V
J 0
(5525 5825);
DISPLAY 0.489362 (5525 5825);
PAINT SKYBLUE (5525 5825);
FORCEPROP 1 LAST VALUE 22UF
J 0
(5525 5875);
DISPLAY 0.489362 (5525 5875);
PAINT SKYBLUE (5525 5875);
FORCEPROP 1 LAST MATERIAL X6S
J 0
(5525 5725);
DISPLAY 0.489362 (5525 5725);
PAINT SKYBLUE (5525 5725);
FORCEPROP 1 LAST TOLERANCE 20%
J 0
(5525 5775);
DISPLAY 0.489362 (5525 5775);
PAINT SKYBLUE (5525 5775);
FORCEPROP 2 LAST CDS_LIB pure_quanta
J 0
(5475 5775);
DISPLAY INVISIBLE (5475 5775);
FORCEPROP 1 LAST PATH I65
J 0
(5525 5925);
DISPLAY 0.978723 (5525 5925);
PAINT WHITE (5525 5925);
DISPLAY INVISIBLE (5525 5925);
FORCEPROP 1 LAST PART_NUMBER CH6223MEA01
J 0
(5525 5625);
DISPLAY 0.489362 (5525 5625);
PAINT SKYBLUE (5525 5625);
DISPLAY INVISIBLE (5525 5625);
FORCEADD Q_CAP..1
(5850 5775);
FORCEPROP 1 LAST LOCATION PC139_5
J 0
(5900 5925);
DISPLAY 0.489362 (5900 5925);
PAINT SKYBLUE (5900 5925);
FORCEPROP 0 LAST $SEC 1
J 0
(5900 5975);
DISPLAY 0.680851 (5900 5975);
PAINT MONO (5900 5975);
DISPLAY INVISIBLE (5900 5975);
FORCEPROP 0 LAST CDS_SEC 1
J 0
(5900 5975);
DISPLAY 1.021277 (5900 5975);
DISPLAY INVISIBLE (5900 5975);
FORCEPROP 1 LASTPIN (5850 5875) $PN 1
J 0
(5860 5855);
DISPLAY 0.489362 (5860 5855);
PAINT MONO (5860 5855);
FORCEPROP 1 LASTPIN (5850 5675) $PN 2
J 0
(5860 5655);
DISPLAY 0.489362 (5860 5655);
PAINT MONO (5860 5655);
FORCEPROP 1 LAST VALUE 22UF
J 0
(5900 5875);
DISPLAY 0.489362 (5900 5875);
PAINT SKYBLUE (5900 5875);
FORCEPROP 1 LAST MATERIAL X6S
J 0
(5900 5725);
DISPLAY 0.489362 (5900 5725);
PAINT SKYBLUE (5900 5725);
FORCEPROP 1 LAST PACK_TYPE C0805
J 0
(5900 5675);
DISPLAY 0.489362 (5900 5675);
PAINT SKYBLUE (5900 5675);
FORCEPROP 1 LAST VOLTAGE 16V
J 0
(5900 5825);
DISPLAY 0.489362 (5900 5825);
PAINT SKYBLUE (5900 5825);
FORCEPROP 1 LAST TOLERANCE 20%
J 0
(5900 5775);
DISPLAY 0.489362 (5900 5775);
PAINT SKYBLUE (5900 5775);
FORCEPROP 2 LAST CDS_LIB pure_quanta
J 0
(5850 5775);
DISPLAY INVISIBLE (5850 5775);
FORCEPROP 1 LAST PATH I66
J 0
(5900 5925);
DISPLAY 0.978723 (5900 5925);
PAINT WHITE (5900 5925);
DISPLAY INVISIBLE (5900 5925);
FORCEPROP 1 LAST PART_NUMBER CH6223MEA01
J 0
(5900 5625);
DISPLAY 0.489362 (5900 5625);
PAINT SKYBLUE (5900 5625);
DISPLAY INVISIBLE (5900 5625);
FORCEADD VCC_CORE..1
(5850 6125);
FORCEPROP 3 LASTPIN (5850 6075) SIG_NAME SW_P12V_AUX_PVDDCR_CPU1_P0_FLT\g
J 0
(5860 6085);
DISPLAY 0.659574 (5860 6085);
PAINT MONO (5860 6085);
DISPLAY INVISIBLE (5860 6085);
FORCEPROP 1 LAST HDL_POWER SW_P12V_AUX_PVDDCR_CPU1_P0_FLT
J 1
(5850 6175);
DISPLAY 0.489362 (5850 6175);
PAINT GREEN (5850 6175);
FORCEPROP 2 LAST CDS_LIB pure_quanta_power
J 0
(5850 6125);
DISPLAY INVISIBLE (5850 6125);
FORCEPROP 1 LAST PATH I67
J 0
(5900 6150);
DISPLAY 0.872340 (5900 6150);
PAINT AQUA (5900 6150);
DISPLAY INVISIBLE (5900 6150);
FORCEADD OFFPAGE..3
(7175 4625);
FORCEPROP 2 LAST $XR0 201 
J 0
(7419 4625);
DISPLAY 0.638298 (7419 4625);
PAINT MONO (7419 4625);
FORCEPROP 2 LAST CDS_LIB standard
J 0
(7175 4625);
DISPLAY INVISIBLE (7175 4625);
FORCEPROP 1 LAST OFFPAGE TRUE
J 0
(7500 4500);
DISPLAY 0.872340 (7500 4500);
PAINT GREEN (7500 4500);
DISPLAY INVISIBLE (7500 4500);
FORCEPROP 1 LAST COMMENT_BODY TRUE
J 0
(7125 4525);
DISPLAY 0.872340 (7125 4525);
PAINT GREEN (7125 4525);
DISPLAY INVISIBLE (7125 4525);
FORCEPROP 2 LAST PATH I68
J 0
(7425 4675);
DISPLAY 0.680851 (7425 4675);
DISPLAY INVISIBLE (7425 4675);
FORCEADD Q_CAP..1
(7700 4675);
FORCEPROP 1 LAST LOCATION PC140_5
J 0
(7750 4800);
DISPLAY 0.489362 (7750 4800);
PAINT SKYBLUE (7750 4800);
FORCEPROP 0 LAST $SEC 1
J 0
(7750 4850);
DISPLAY 0.680851 (7750 4850);
PAINT MONO (7750 4850);
DISPLAY INVISIBLE (7750 4850);
FORCEPROP 0 LAST CDS_SEC 1
J 0
(7750 4850);
DISPLAY 1.021277 (7750 4850);
DISPLAY INVISIBLE (7750 4850);
FORCEPROP 1 LASTPIN (7700 4775) $PN 1
J 0
(7710 4755);
DISPLAY 0.489362 (7710 4755);
PAINT MONO (7710 4755);
FORCEPROP 1 LASTPIN (7700 4575) $PN 2
J 0
(7710 4555);
DISPLAY 0.489362 (7710 4555);
PAINT MONO (7710 4555);
FORCEPROP 1 LAST PACK_TYPE C0805
J 0
(7750 4550);
DISPLAY 0.489362 (7750 4550);
PAINT SKYBLUE (7750 4550);
FORCEPROP 1 LAST MATERIAL X6S
J 0
(7750 4600);
DISPLAY 0.489362 (7750 4600);
PAINT SKYBLUE (7750 4600);
FORCEPROP 1 LAST TOLERANCE 20%
J 0
(7750 4650);
DISPLAY 0.489362 (7750 4650);
PAINT SKYBLUE (7750 4650);
FORCEPROP 1 LAST VALUE 22UF
J 0
(7750 4750);
DISPLAY 0.489362 (7750 4750);
PAINT SKYBLUE (7750 4750);
FORCEPROP 1 LAST VOLTAGE 4V
J 0
(7750 4700);
DISPLAY 0.489362 (7750 4700);
PAINT SKYBLUE (7750 4700);
FORCEPROP 2 LAST CDS_LIB pure_quanta
J 0
(7700 4675);
DISPLAY INVISIBLE (7700 4675);
FORCEPROP 1 LAST PATH I69
J 0
(7750 4825);
DISPLAY 0.978723 (7750 4825);
PAINT WHITE (7750 4825);
DISPLAY INVISIBLE (7750 4825);
FORCEPROP 1 LAST PART_NUMBER CH622KMEA03
J 0
(7750 4500);
DISPLAY 0.489362 (7750 4500);
PAINT SKYBLUE (7750 4500);
DISPLAY INVISIBLE (7750 4500);
FORCEADD OFFPAGE..1
(1925 2125);
FORCEPROP 2 LAST $XR5 206 
J 0
(1043 2125);
DISPLAY 0.638298 (1043 2125);
PAINT MONO (1043 2125);
FORCEPROP 2 LAST $XR4 205 
J 0
(1163 2125);
DISPLAY 0.638298 (1163 2125);
PAINT MONO (1163 2125);
FORCEPROP 2 LAST $XR3 203 
J 0
(1283 2125);
DISPLAY 0.638298 (1283 2125);
PAINT MONO (1283 2125);
FORCEPROP 2 LAST $XR2 202 
J 0
(1403 2125);
DISPLAY 0.638298 (1403 2125);
PAINT MONO (1403 2125);
FORCEPROP 2 LAST $XR1 201 
J 0
(1523 2125);
DISPLAY 0.638298 (1523 2125);
PAINT MONO (1523 2125);
FORCEPROP 2 LAST $XR0 200 
J 0
(1643 2125);
DISPLAY 0.638298 (1643 2125);
PAINT MONO (1643 2125);
FORCEPROP 2 LAST CDS_LIB standard
J 0
(1925 2125);
DISPLAY INVISIBLE (1925 2125);
FORCEPROP 1 LAST OFFPAGE TRUE
J 0
(2250 2000);
DISPLAY 0.872340 (2250 2000);
PAINT GREEN (2250 2000);
DISPLAY INVISIBLE (2250 2000);
FORCEPROP 1 LAST COMMENT_BODY TRUE
J 0
(2050 2025);
DISPLAY 0.872340 (2050 2025);
PAINT GREEN (2050 2025);
DISPLAY INVISIBLE (2050 2025);
FORCEPROP 2 LAST PATH I7
J 0
(1675 2175);
DISPLAY 0.680851 (1675 2175);
DISPLAY INVISIBLE (1675 2175);
FORCEADD Q_CAP..1
(8125 4675);
FORCEPROP 1 LAST LOCATION PC141_5
J 0
(8175 4800);
DISPLAY 0.489362 (8175 4800);
PAINT SKYBLUE (8175 4800);
FORCEPROP 0 LAST $SEC 1
J 0
(8175 4850);
DISPLAY 0.680851 (8175 4850);
PAINT MONO (8175 4850);
DISPLAY INVISIBLE (8175 4850);
FORCEPROP 0 LAST CDS_SEC 1
J 0
(8175 4850);
DISPLAY 1.021277 (8175 4850);
DISPLAY INVISIBLE (8175 4850);
FORCEPROP 1 LASTPIN (8125 4775) $PN 1
J 0
(8135 4755);
DISPLAY 0.489362 (8135 4755);
PAINT MONO (8135 4755);
FORCEPROP 1 LASTPIN (8125 4575) $PN 2
J 0
(8135 4555);
DISPLAY 0.489362 (8135 4555);
PAINT MONO (8135 4555);
FORCEPROP 1 LAST PACK_TYPE C0805
J 0
(8175 4550);
DISPLAY 0.489362 (8175 4550);
PAINT SKYBLUE (8175 4550);
FORCEPROP 1 LAST MATERIAL X6S
J 0
(8175 4600);
DISPLAY 0.489362 (8175 4600);
PAINT SKYBLUE (8175 4600);
FORCEPROP 1 LAST TOLERANCE 20%
J 0
(8175 4650);
DISPLAY 0.489362 (8175 4650);
PAINT SKYBLUE (8175 4650);
FORCEPROP 1 LAST VALUE 22UF
J 0
(8175 4750);
DISPLAY 0.489362 (8175 4750);
PAINT SKYBLUE (8175 4750);
FORCEPROP 1 LAST VOLTAGE 4V
J 0
(8175 4700);
DISPLAY 0.489362 (8175 4700);
PAINT SKYBLUE (8175 4700);
FORCEPROP 2 LAST CDS_LIB pure_quanta
J 0
(8125 4675);
DISPLAY INVISIBLE (8125 4675);
FORCEPROP 1 LAST PATH I70
J 0
(8175 4825);
DISPLAY 0.978723 (8175 4825);
PAINT WHITE (8175 4825);
DISPLAY INVISIBLE (8175 4825);
FORCEPROP 1 LAST PART_NUMBER CH622KMEA03
J 0
(8175 4500);
DISPLAY 0.489362 (8175 4500);
PAINT SKYBLUE (8175 4500);
DISPLAY INVISIBLE (8175 4500);
FORCEADD VCC_CORE..1
(8125 5025);
FORCEPROP 3 LASTPIN (8125 4975) SIG_NAME PVDDCR_CPU1_P0\g
J 0
(8135 4985);
DISPLAY 0.659574 (8135 4985);
PAINT MONO (8135 4985);
DISPLAY INVISIBLE (8135 4985);
FORCEPROP 1 LAST HDL_POWER PVDDCR_CPU1_P0
J 1
(8125 5075);
DISPLAY 0.489362 (8125 5075);
PAINT GREEN (8125 5075);
FORCEPROP 2 LAST CDS_LIB pure_quanta_power
J 0
(8125 5025);
DISPLAY INVISIBLE (8125 5025);
FORCEPROP 1 LAST PATH I71
J 0
(8175 5050);
DISPLAY 0.872340 (8175 5050);
PAINT AQUA (8175 5050);
DISPLAY INVISIBLE (8175 5050);
FORCEADD Q_CAP..1
(4800 2025);
FORCEPROP 1 LAST LOCATION PC154
J 0
(4850 2125);
DISPLAY 0.489362 (4850 2125);
PAINT SKYBLUE (4850 2125);
FORCEPROP 0 LAST $SEC 1
J 0
(4850 2175);
DISPLAY 0.680851 (4850 2175);
PAINT MONO (4850 2175);
DISPLAY INVISIBLE (4850 2175);
FORCEPROP 0 LAST CDS_SEC 1
J 0
(4850 2175);
DISPLAY 1.021277 (4850 2175);
DISPLAY INVISIBLE (4850 2175);
FORCEPROP 1 LASTPIN (4800 2125) $PN 1
J 0
(4810 2105);
DISPLAY 0.489362 (4810 2105);
PAINT MONO (4810 2105);
FORCEPROP 1 LASTPIN (4800 1925) $PN 2
J 0
(4810 1905);
DISPLAY 0.489362 (4810 1905);
PAINT MONO (4810 1905);
FORCEPROP 1 LAST VALUE 560PF
J 0
(4850 2075);
DISPLAY 0.489362 (4850 2075);
PAINT SKYBLUE (4850 2075);
FORCEPROP 1 LAST VOLTAGE 50V
J 0
(4850 2025);
DISPLAY 0.489362 (4850 2025);
PAINT SKYBLUE (4850 2025);
FORCEPROP 1 LAST TOLERANCE 10%
J 0
(4850 1975);
DISPLAY 0.489362 (4850 1975);
PAINT SKYBLUE (4850 1975);
FORCEPROP 1 LAST MATERIAL EMPTY
J 0
(4850 1925);
DISPLAY 0.489362 (4850 1925);
PAINT RED (4850 1925);
FORCEPROP 1 LAST PACK_TYPE C0402
J 0
(4850 1825);
DISPLAY 0.489362 (4850 1825);
PAINT SKYBLUE (4850 1825);
FORCEPROP 2 LAST CDS_LIB pure_quanta
J 0
(4800 2025);
DISPLAY INVISIBLE (4800 2025);
FORCEPROP 1 LAST PATH I72
J 0
(4850 2175);
DISPLAY 0.978723 (4850 2175);
PAINT WHITE (4850 2175);
DISPLAY INVISIBLE (4850 2175);
FORCEPROP 1 LAST PART_NUMBER CH1566K1B09
J 0
(4850 1875);
DISPLAY 0.489362 (4850 1875);
PAINT SKYBLUE (4850 1875);
DISPLAY INVISIBLE (4850 1875);
FORCEADD ISL99390FRZTR5935..1
(3375 2225);
FORCEPROP 1 LAST LOCATION PU11
J 0
(3075 3100);
DISPLAY 0.489362 (3075 3100);
PAINT SKYBLUE (3075 3100);
FORCEPROP 0 LAST $SEC 1
J 0
(3075 3300);
DISPLAY 0.680851 (3075 3300);
PAINT MONO (3075 3300);
DISPLAY INVISIBLE (3075 3300);
FORCEPROP 2 LAST CDS_SEC 1
J 0
(3075 3275);
DISPLAY 1.021277 (3075 3275);
DISPLAY INVISIBLE (3075 3275);
FORCEPROP 0 LASTPIN (3775 1775) $PN 2
J 0
(3785 1785);
DISPLAY 0.489362 (3785 1785);
PAINT MONO (3785 1785);
FORCEPROP 0 LASTPIN (3775 2575) $PN 33
J 0
(3785 2585);
DISPLAY 0.489362 (3785 2585);
PAINT MONO (3785 2585);
FORCEPROP 0 LASTPIN (2925 1975) $PN 31
J 2
(2915 1985);
DISPLAY 0.489362 (2915 1985);
PAINT MONO (2915 1985);
FORCEPROP 0 LASTPIN (2925 2375) $PN 35
J 2
(2915 2385);
DISPLAY 0.489362 (2915 2385);
PAINT MONO (2915 2385);
FORCEPROP 0 LASTPIN (3775 1925) $PN 6
J 0
(3785 1935);
DISPLAY 0.489362 (3785 1935);
PAINT MONO (3785 1935);
FORCEPROP 0 LASTPIN (3775 1875) $PN 41
J 0
(3785 1885);
DISPLAY 0.489362 (3785 1885);
PAINT MONO (3785 1885);
FORCEPROP 0 LASTPIN (2925 2225) $PN 38
J 2
(2915 2235);
DISPLAY 0.489362 (2915 2235);
PAINT MONO (2915 2235);
FORCEPROP 0 LASTPIN (2925 1925) $PN 37
J 2
(2915 1935);
DISPLAY 0.489362 (2915 1935);
PAINT MONO (2915 1935);
FORCEPROP 0 LASTPIN (3775 1725) $PN 5
J 0
(3785 1735);
DISPLAY 0.489362 (3785 1735);
PAINT MONO (3785 1735);
FORCEPROP 0 LASTPIN (3775 1675) $PN 7_9-20_24
J 0
(3785 1685);
DISPLAY 0.489362 (3785 1685);
PAINT MONO (3785 1685);
FORCEPROP 0 LASTPIN (3775 1625) $PN 40
J 0
(3785 1635);
DISPLAY 0.489362 (3785 1635);
PAINT MONO (3785 1635);
FORCEPROP 0 LASTPIN (3775 2325) $PN 32
J 0
(3785 2335);
DISPLAY 0.489362 (3785 2335);
PAINT MONO (3785 2335);
FORCEPROP 0 LASTPIN (2925 2875) $PN 4
J 2
(2915 2885);
DISPLAY 0.489362 (2915 2885);
PAINT MONO (2915 2885);
FORCEPROP 0 LASTPIN (2925 1625) $PN 34
J 2
(2915 1635);
DISPLAY 0.489362 (2915 1635);
PAINT MONO (2915 1635);
FORCEPROP 0 LASTPIN (2925 2125) $PN 39
J 2
(2915 2135);
DISPLAY 0.489362 (2915 2135);
PAINT MONO (2915 2135);
FORCEPROP 0 LASTPIN (3775 2225) $PN 10_19
J 0
(3785 2235);
DISPLAY 0.489362 (3785 2235);
PAINT MONO (3785 2235);
FORCEPROP 0 LASTPIN (2925 1725) $PN 36
J 2
(2915 1735);
DISPLAY 0.489362 (2915 1735);
PAINT MONO (2915 1735);
FORCEPROP 0 LASTPIN (2925 2575) $PN 3
J 2
(2915 2585);
DISPLAY 0.489362 (2915 2585);
PAINT MONO (2915 2585);
FORCEPROP 0 LASTPIN (3775 2875) $PN 25_29
J 0
(3785 2885);
DISPLAY 0.489362 (3785 2885);
PAINT MONO (3785 2885);
FORCEPROP 0 LASTPIN (3775 2825) $PN 30
J 0
(3785 2835);
DISPLAY 0.489362 (3785 2835);
PAINT MONO (3785 2835);
FORCEPROP 0 LASTPIN (3775 1975) $PN 1
J 0
(3785 1985);
DISPLAY 0.489362 (3785 1985);
PAINT MONO (3785 1985);
FORCEPROP 2 LAST PART_TYPE SMLF
J 0
(3075 3250);
DISPLAY 0.638298 (3075 3250);
FORCEPROP 2 LAST VALUE ISL99390FRZ-TR5935
J 0
(3075 3200);
DISPLAY 0.489362 (3075 3200);
PAINT SKYBLUE (3075 3200);
FORCEPROP 1 LAST MATERIAL IC
J 0
(3075 2950);
DISPLAY 0.489362 (3075 2950);
PAINT SKYBLUE (3075 2950);
FORCEPROP 2 LAST CDS_LIB pure_quanta
J 0
(3375 2225);
DISPLAY INVISIBLE (3375 2225);
FORCEPROP 1 LAST CDS_LMAN_SYM_OUTLINE -300,700,250,-650
J 0
(3375 2225);
DISPLAY 0.468085 (3375 2225);
PAINT GREEN (3375 2225);
DISPLAY INVISIBLE (3375 2225);
FORCEPROP 1 LAST NEEDS_NO_SIZE TRUE
J 0
(3375 2225);
DISPLAY 0.723404 (3375 2225);
PAINT GREEN (3375 2225);
DISPLAY INVISIBLE (3375 2225);
FORCEPROP 1 LAST PATH I73
J 0
(3375 2225);
DISPLAY 0.723404 (3375 2225);
PAINT GREEN (3375 2225);
DISPLAY INVISIBLE (3375 2225);
FORCEPROP 1 LAST PART_NUMBER AL099390004
J 0
(3075 3025);
DISPLAY 0.489362 (3075 3025);
PAINT SKYBLUE (3075 3025);
DISPLAY INVISIBLE (3075 3025);
FORCEADD OFFPAGE..5
(1925 2225);
FORCEPROP 2 LAST $XR0 200 
J 0
(1670 2225);
DISPLAY 0.638298 (1670 2225);
PAINT MONO (1670 2225);
FORCEPROP 2 LAST CDS_LIB standard
J 0
(1925 2225);
DISPLAY INVISIBLE (1925 2225);
FORCEPROP 1 LAST OFFPAGE TRUE
J 0
(2250 2100);
DISPLAY 0.872340 (2250 2100);
PAINT GREEN (2250 2100);
DISPLAY INVISIBLE (2250 2100);
FORCEPROP 1 LAST COMMENT_BODY TRUE
J 0
(2025 2150);
DISPLAY 0.872340 (2025 2150);
PAINT GREEN (2025 2150);
DISPLAY INVISIBLE (2025 2150);
FORCEPROP 2 LAST PATH I8
J 0
(1650 2275);
DISPLAY 0.680851 (1650 2275);
DISPLAY INVISIBLE (1650 2275);
FORCEADD UNIVERSAL_GND..1
(975 4300);
FORCEPROP 3 LASTPIN (975 4350) SIG_NAME GND\g
J 0
(985 4360);
DISPLAY 0.659574 (985 4360);
PAINT MONO (985 4360);
DISPLAY INVISIBLE (985 4360);
FORCEPROP 2 LAST CDS_LIB pure_quanta_power
J 0
(975 4300);
DISPLAY INVISIBLE (975 4300);
FORCEPROP 1 LAST HDL_POWER GND
J 1
(1000 4225);
DISPLAY 0.872340 (1000 4225);
PAINT GREEN (1000 4225);
DISPLAY INVISIBLE (1000 4225);
FORCEPROP 1 LAST PATH I9
J 0
(1050 4300);
DISPLAY 0.872340 (1050 4300);
PAINT AQUA (1050 4300);
DISPLAY INVISIBLE (1050 4300);
FORCEADD DNS..1
(1450 1700);
PAINT RED (1450 1700);
FORCEPROP 2 LAST CDS_LIB mstr_misc
J 0
(1450 1700);
PAINT MONO (1450 1700);
DISPLAY INVISIBLE (1450 1700);
FORCEPROP 1 LAST COMMENT_BODY TRUE
R 1
J 0
(1525 1475);
DISPLAY 0.872340 (1525 1475);
PAINT GREEN (1525 1475);
DISPLAY INVISIBLE (1525 1475);
FORCEADD DNS..1
(1475 4350);
PAINT RED (1475 4350);
FORCEPROP 2 LAST CDS_LIB mstr_misc
J 0
(1475 4350);
PAINT MONO (1475 4350);
DISPLAY INVISIBLE (1475 4350);
FORCEPROP 1 LAST COMMENT_BODY TRUE
R 1
J 0
(1550 4125);
DISPLAY 0.872340 (1550 4125);
PAINT GREEN (1550 4125);
DISPLAY INVISIBLE (1550 4125);
FORCEADD DNS..1
(4775 1475);
PAINT RED (4775 1475);
FORCEPROP 2 LAST CDS_LIB mstr_misc
J 0
(4775 1475);
DISPLAY INVISIBLE (4775 1475);
FORCEPROP 1 LAST COMMENT_BODY TRUE
R 1
J 0
(4850 1250);
DISPLAY 0.872340 (4850 1250);
PAINT GREEN (4850 1250);
DISPLAY INVISIBLE (4850 1250);
FORCEADD DNS..1
(4875 4150);
PAINT RED (4875 4150);
FORCEPROP 2 LAST CDS_LIB mstr_misc
J 0
(4875 4150);
DISPLAY INVISIBLE (4875 4150);
FORCEPROP 1 LAST COMMENT_BODY TRUE
R 1
J 0
(4950 3925);
DISPLAY 0.872340 (4950 3925);
PAINT GREEN (4950 3925);
DISPLAY INVISIBLE (4950 3925);
FORCEADD DNS..1
(4875 4675);
PAINT RED (4875 4675);
FORCEPROP 2 LAST CDS_LIB mstr_misc
J 0
(4875 4675);
DISPLAY INVISIBLE (4875 4675);
FORCEPROP 1 LAST COMMENT_BODY TRUE
R 1
J 0
(4950 4450);
DISPLAY 0.872340 (4950 4450);
PAINT GREEN (4950 4450);
DISPLAY INVISIBLE (4950 4450);
FORCEADD DNS..1
(4775 2025);
PAINT RED (4775 2025);
FORCEPROP 2 LAST CDS_LIB mstr_misc
J 0
(4775 2025);
DISPLAY INVISIBLE (4775 2025);
FORCEPROP 1 LAST COMMENT_BODY TRUE
R 1
J 0
(4850 1800);
DISPLAY 0.872340 (4850 1800);
PAINT GREEN (4850 1800);
DISPLAY INVISIBLE (4850 1800);
FORCEADD QUANTA_TITLE_BLOCK_C..1
(9400 100);
FORCEPROP 0 LAST CDS_CON_LAST_MODIFIED Thu Sep 14 16:12:19 2023
J 0
(7515 115);
DISPLAY INVISIBLE (7515 115);
FORCEPROP 1 LAST CUSTOM_TXT_CDS <CON_LAST_MODIFIED>
J 0
(7515 115);
DISPLAY 0.978723 (7515 115);
FORCEPROP 2 LAST CUSTOM_TXT_CDS <XR_PAGE_TITLE>
J 0
(1510 5350);
DISPLAY 0.638298 (1510 5350);
PAINT PINK (1510 5350);
DISPLAY INVISIBLE (1510 5350);
FORCEPROP 1 LAST CUSTOM_TXT_CDS <NAME_2>
J 0
(6225 150);
FORCEPROP 1 LAST CUSTOM_TXT_CDS <NAME_1>
J 0
(6225 275);
FORCEPROP 1 LAST CUSTOM_TXT_CDS <Q_NUMBER>
J 0
(7997 203);
DISPLAY 1.212766 (7997 203);
FORCEPROP 1 LAST CUSTOM_TXT_CDS <Q_PROJ>
J 0
(7018 202);
DISPLAY 1.212766 (7018 202);
FORCEPROP 1 LAST CUSTOM_TXT_CDS <Q_REV>
J 0
(9216 203);
DISPLAY 1.212766 (9216 203);
FORCEPROP 1 LAST CUSTOM_TXT_CDS <CON_PAGE_NUM> OF <CON_TOTAL_PAGES>
J 0
(8954 118);
DISPLAY 0.978723 (8954 118);
FORCEPROP 1 LAST Q_TITLE PVDDCR_CPU1_P0 VR PHASE 5&6
J 0
(100 175);
DISPLAY 2.446809 (100 175);
PAINT GREEN (100 175);
FORCEPROP 2 LAST PAGE_BORDER TRUE
J 0
(1510 5350);
DISPLAY 0.638298 (1510 5350);
PAINT PINK (1510 5350);
DISPLAY INVISIBLE (1510 5350);
FORCEPROP 2 LAST CDS_LIB pure_quanta
J 0
(9400 100);
DISPLAY INVISIBLE (9400 100);
FORCEPROP 1 LAST CDS_LMAN_SYM_OUTLINE -9475,6775,100,-125
J 0
(9400 100);
DISPLAY 0.468085 (9400 100);
PAINT GREEN (9400 100);
DISPLAY INVISIBLE (9400 100);
FORCEPROP 2 LAST CDS_XR_PAGE_TITLE CR-203 : @T6G_MB_LIB.T6G(SCH_1):PAGE203
J 0
(1510 5350);
DISPLAY 0.638298 (1510 5350);
PAINT PINK (1510 5350);
DISPLAY INVISIBLE (1510 5350);
FORCEPROP 1 LAST Q_DEPT BU9
J 1
(5637 149);
DISPLAY 1.957447 (5637 149);
PAINT GREEN (5637 149);
DISPLAY INVISIBLE (5637 149);
FORCEPROP 1 LAST COMMENT_BODY TRUE
J 0
(9412 87);
DISPLAY 0.978723 (9412 87);
PAINT GREEN (9412 87);
DISPLAY INVISIBLE (9412 87);
WIRE 16 -1 (950 1700)(950 1750);
WIRE 16 -1 (1900 2550)(1900 2500);
WIRE 16 -1 (1475 4275)(1475 4200);
WIRE 16 -1 (2250 3125)(2250 3000);
WIRE 16 -1 (1925 5200)(1925 5150);
WIRE 16 -1 (1450 1625)(1450 1550);
WIRE 16 -1 (2275 5775)(2275 5650);
WIRE 16 -1 (4800 1375)(4800 1300);
WIRE 16 -1 (5225 1975)(5150 1975);
WIRE 16 -1 (5150 1975)(5150 1925);
WIRE 16 -1 (4900 4050)(4900 3975);
WIRE 16 -1 (975 4350)(975 4400);
WIRE 16 -1 (5825 3225)(5825 3375);
WIRE 16 -1 (5825 3425)(5825 3375);
WIRE 16 -1 (5450 3375)(5825 3375);
WIRE 16 -1 (5450 3225)(5450 3375);
WIRE 16 -1 (5050 3375)(5450 3375);
WIRE 16 -1 (5050 3375)(5050 3225);
WIRE 16 -1 (4650 3375)(5050 3375);
WIRE 16 -1 (4650 3225)(4650 3375);
WIRE 16 -1 (4650 3375)(4225 3375);
WIRE 16 -1 (4225 3225)(4225 3375);
WIRE 16 -1 (4225 3375)(3950 3375);
WIRE 16 -1 (3950 3375)(3950 2875);
WIRE 16 -1 (3950 2825)(3950 2875);
WIRE 16 -1 (3775 2875)(3950 2875);
WIRE 16 -1 (3775 2825)(3950 2825);
WIRE 16 -1 (5825 3025)(5825 2875);
WIRE 16 -1 (5825 2825)(5825 2875);
WIRE 16 -1 (5450 2875)(5825 2875);
WIRE 16 -1 (5450 3025)(5450 2875);
WIRE 16 -1 (5050 2875)(5450 2875);
WIRE 16 -1 (5050 3025)(5050 2875);
WIRE 16 -1 (5050 2875)(4650 2875);
WIRE 16 -1 (4650 3025)(4650 2875);
WIRE 16 -1 (4225 2875)(4650 2875);
WIRE 16 -1 (4225 3025)(4225 2875);
WIRE 16 -1 (5950 3800)(4625 3800);
FORCEPROP 2 LAST SIG_NAME PVDDCR_CPU1_P0_VOS5
J 0
(3915 4650);
DISPLAY 0.489362 (3915 4650);
FORCEPROP 2 LASTPROP $XRERR UNIQUE?
J 0
(3675 4650);
DISPLAY 0.638298 (3675 4650);
PAINT MONO (3675 4650);
DISPLAY INVISIBLE (3675 4650);
WIRE 16 -1 (4625 4625)(4625 3800);
WIRE 16 -1 (3800 4625)(4625 4625);
WIRE 16 -1 (4900 4775)(4900 4875);
WIRE 16 -1 (4900 4875)(5900 4875);
WIRE 16 -1 (3800 4875)(4900 4875);
FORCEPROP 2 LAST SIG_NAME SW_PVDDCR_CPU1_P0_SW5
J 0
(3990 4885);
DISPLAY 0.489362 (3990 4885);
FORCEPROP 2 LASTPROP $XRERR UNIQUE?
J 0
(3750 4885);
DISPLAY 0.638298 (3750 4885);
PAINT MONO (3750 4885);
DISPLAY INVISIBLE (3750 4885);
WIRE 16 -1 (5375 4975)(5375 5000);
WIRE 16 -1 (3800 4975)(5375 4975);
FORCEPROP 2 LAST SIG_NAME SW_PVDDCR_CPU1_P0_BOOTR5
J 0
(3990 4985);
DISPLAY 0.489362 (3990 4985);
FORCEPROP 2 LASTPROP $XRERR UNIQUE?
J 0
(3750 4985);
DISPLAY 0.638298 (3750 4985);
PAINT MONO (3750 4985);
DISPLAY INVISIBLE (3750 4985);
WIRE 16 -1 (2925 2875)(2575 2875);
WIRE 16 -1 (2575 2875)(2575 3425);
WIRE 16 -1 (2575 3425)(2250 3425);
WIRE 16 -1 (2250 3325)(2250 3425);
WIRE 16 -1 (2250 3425)(1900 3425);
WIRE 16 -1 (1900 3575)(1900 3425);
WIRE 16 -1 (1900 3300)(1900 3425);
WIRE 16 -1 (3775 1775)(4025 1775);
WIRE 16 -1 (4025 1775)(4025 1725);
WIRE 16 -1 (4025 1725)(4025 1675);
WIRE 16 -1 (3775 1725)(4025 1725);
WIRE 16 -1 (4025 1675)(4025 1625);
WIRE 16 -1 (3775 1675)(4025 1675);
WIRE 16 -1 (3775 1625)(4025 1625);
WIRE 16 -1 (4025 1625)(4025 1550);
WIRE 16 -1 (3800 4325)(4050 4325);
WIRE 16 -1 (4050 4375)(4050 4325);
WIRE 16 -1 (4050 4325)(4050 4275);
WIRE 16 -1 (3800 4275)(4050 4275);
WIRE 16 -1 (4050 4275)(4050 4200);
WIRE 16 -1 (4050 4425)(4050 4375);
WIRE 16 -1 (3800 4375)(4050 4375);
WIRE 16 -1 (3800 4425)(4050 4425);
WIRE 16 -1 (2950 5525)(2600 5525);
WIRE 16 -1 (2600 5525)(2600 6075);
WIRE 16 -1 (2600 6075)(2275 6075);
WIRE 16 -1 (2275 5975)(2275 6075);
WIRE 16 -1 (2275 6075)(1925 6075);
WIRE 16 -1 (1925 6225)(1925 6075);
WIRE 16 -1 (1925 5950)(1925 6075);
WIRE 16 -1 (8100 1925)(8100 1800);
WIRE 16 -1 (8100 1725)(8100 1800);
WIRE 16 -1 (8100 1800)(7675 1800);
WIRE 16 -1 (7675 1800)(7675 1925);
WIRE 16 -1 (7675 2225)(7375 2225);
WIRE 16 -1 (7675 2225)(8100 2225);
WIRE 16 -1 (7675 2225)(7675 2125);
WIRE 16 -1 (7375 2225)(6700 2225);
WIRE 16 -1 (7375 2225)(7375 1100);
WIRE 16 -1 (7375 1100)(6075 1100);
WIRE 16 -1 (8100 2325)(8100 2225);
WIRE 16 -1 (8100 2125)(8100 2225);
WIRE 16 -1 (8125 4575)(8125 4450);
WIRE 16 -1 (8125 4375)(8125 4450);
WIRE 16 -1 (8125 4450)(7700 4450);
WIRE 16 -1 (7700 4450)(7700 4575);
WIRE 16 -1 (4250 5675)(4250 5525);
WIRE 16 -1 (4250 5525)(4675 5525);
WIRE 16 -1 (4675 5675)(4675 5525);
WIRE 16 -1 (5075 5525)(4675 5525);
WIRE 16 -1 (5075 5525)(5475 5525);
WIRE 16 -1 (5075 5675)(5075 5525);
WIRE 16 -1 (5475 5525)(5850 5525);
WIRE 16 -1 (5475 5675)(5475 5525);
WIRE 16 -1 (5850 5675)(5850 5525);
WIRE 16 -1 (5850 5475)(5850 5525);
WIRE 16 -1 (3800 5475)(3975 5475);
WIRE 16 -1 (3975 5475)(3975 5525);
WIRE 16 -1 (3975 6025)(3975 5525);
WIRE 16 -1 (3800 5525)(3975 5525);
WIRE 16 -1 (4250 6025)(3975 6025);
WIRE 16 -1 (4675 6025)(4250 6025);
WIRE 16 -1 (4250 5875)(4250 6025);
WIRE 16 -1 (4675 6025)(5075 6025);
WIRE 16 -1 (4675 5875)(4675 6025);
WIRE 16 -1 (5075 6025)(5475 6025);
WIRE 16 -1 (5075 6025)(5075 5875);
WIRE 16 -1 (5475 6025)(5850 6025);
WIRE 16 -1 (5475 5875)(5475 6025);
WIRE 16 -1 (5850 6075)(5850 6025);
WIRE 16 -1 (5850 5875)(5850 6025);
WIRE 16 -1 (7700 4875)(7400 4875);
WIRE 16 -1 (7700 4875)(8125 4875);
WIRE 16 -1 (7700 4875)(7700 4775);
WIRE 16 -1 (7400 4875)(6700 4875);
WIRE 16 -1 (7400 4875)(7400 3800);
WIRE 16 -1 (7400 3800)(6150 3800);
WIRE 16 -1 (8125 4975)(8125 4875);
WIRE 16 -1 (8125 4775)(8125 4875);
WIRE 16 -1 (3800 5225)(4550 5225);
FORCEPROP 2 LAST SIG_NAME SW_PVDDCR_CPU1_P0_BOOT5
J 0
(4015 5235);
DISPLAY 0.489362 (4015 5235);
FORCEPROP 2 LASTPROP $XRERR UNIQUE?
J 0
(3775 5235);
DISPLAY 0.638298 (3775 5235);
PAINT MONO (3775 5235);
DISPLAY INVISIBLE (3775 5235);
WIRE 16 -1 (5375 5225)(5375 5200);
WIRE 16 -1 (4750 5225)(5375 5225);
FORCEPROP 2 LAST SIG_NAME SW_PVDDCR_CPU1_P0_BOOT5_R
J 0
(4840 5235);
DISPLAY 0.489362 (4840 5235);
FORCEPROP 2 LASTPROP $XRERR UNIQUE?
J 0
(4600 5235);
DISPLAY 0.638298 (4600 5235);
PAINT MONO (4600 5235);
DISPLAY INVISIBLE (4600 5235);
WIRE 16 -1 (3775 2575)(4525 2575);
FORCEPROP 2 LAST SIG_NAME SW_PVDDCR_CPU1_P0_BOOT6
J 0
(3990 2585);
DISPLAY 0.489362 (3990 2585);
FORCEPROP 2 LASTPROP $XRERR UNIQUE?
J 0
(3750 2585);
DISPLAY 0.638298 (3750 2585);
PAINT MONO (3750 2585);
DISPLAY INVISIBLE (3750 2585);
WIRE 16 -1 (5350 2575)(5350 2550);
WIRE 16 -1 (4725 2575)(5350 2575);
FORCEPROP 2 LAST SIG_NAME SW_PVDDCR_CPU1_P0_BOOT6_R
J 0
(4815 2585);
DISPLAY 0.489362 (4815 2585);
FORCEPROP 2 LASTPROP $XRERR UNIQUE?
J 0
(4575 2585);
DISPLAY 0.638298 (4575 2585);
PAINT MONO (4575 2585);
DISPLAY INVISIBLE (4575 2585);
WIRE 16 -1 (5350 2325)(5350 2350);
WIRE 16 -1 (3775 2325)(5350 2325);
FORCEPROP 2 LAST SIG_NAME SW_PVDDCR_CPU1_P0_BOOTR6
J 0
(3965 2335);
DISPLAY 0.489362 (3965 2335);
FORCEPROP 2 LASTPROP $XRERR UNIQUE?
J 0
(3725 2335);
DISPLAY 0.638298 (3725 2335);
PAINT MONO (3725 2335);
DISPLAY INVISIBLE (3725 2335);
WIRE 16 -1 (4800 2125)(4800 2225);
WIRE 16 -1 (4800 2225)(5900 2225);
WIRE 16 -1 (3775 2225)(4800 2225);
FORCEPROP 2 LAST SIG_NAME SW_PVDDCR_CPU1_P0_SW6
J 0
(3965 2235);
DISPLAY 0.489362 (3965 2235);
FORCEPROP 2 LASTPROP $XRERR UNIQUE?
J 0
(3725 2235);
DISPLAY 0.638298 (3725 2235);
PAINT MONO (3725 2235);
DISPLAY INVISIBLE (3725 2235);
WIRE 16 -1 (5425 1975)(5900 1975);
WIRE 16 -1 (3775 1875)(4375 1875);
FORCEPROP 2 LAST SIG_NAME NC_PVDDCR_CPU1_P0_GL2_6
J 0
(3890 1885);
DISPLAY 0.489362 (3890 1885);
FORCEPROP 2 LASTPROP $XRERR UNIQUE?
J 0
(4405 1875);
DISPLAY 0.638298 (4405 1875);
PAINT MONO (4405 1875);
DISPLAY INVISIBLE (4405 1875);
WIRE 16 -1 (3775 1975)(4600 1975);
WIRE 16 -1 (4600 1975)(4600 1100);
WIRE 16 -1 (5875 1100)(4600 1100);
FORCEPROP 2 LAST SIG_NAME PVDDCR_CPU1_P0_VOS6
J 0
(3890 2000);
DISPLAY 0.489362 (3890 2000);
FORCEPROP 2 LASTPROP $XRERR UNIQUE?
J 0
(3650 2000);
DISPLAY 0.638298 (3650 2000);
PAINT MONO (3650 2000);
DISPLAY INVISIBLE (3650 2000);
WIRE 16 -1 (2850 4775)(2850 4700);
FORCEPROP 0 LAST CDS_PHYS_NET_NAME PVDDCR_CPU1_P0_VCCS
J 0
(2850 4725);
PAINT MONO (2850 4725);
DISPLAY INVISIBLE (2850 4725);
WIRE 16 -1 (2850 4775)(2950 4775);
WIRE 16 -1 (2000 4775)(2850 4775);
FORCEPROP 2 LAST SIG_NAME PVDDCR_CPU1_P0_VCCS
J 0
(2115 4785);
DISPLAY 0.489362 (2115 4785);
WIRE 16 -1 (2850 4700)(975 4700);
WIRE 16 -1 (975 4700)(975 4600);
WIRE 16 -1 (6700 4625)(7125 4625);
FORCEPROP 2 LAST SIG_NAME IND_CPU1_P0_CPL5
J 0
(6790 4635);
DISPLAY 0.489362 (6790 4635);
WIRE 16 -1 (5425 4625)(5900 4625);
FORCEPROP 2 LAST SIG_NAME IND_CPU1_P0_CPL6
J 0
(5465 4635);
DISPLAY 0.489362 (5465 4635);
WIRE 16 -1 (4900 4575)(4900 4250);
FORCEPROP 2 LAST SIG_NAME SW_PVDDCR_CPU1_P0_SW5_RC
J 0
(4940 4385);
DISPLAY 0.489362 (4940 4385);
FORCEPROP 2 LASTPROP $XRERR UNIQUE?
J 0
(4700 4385);
DISPLAY 0.638298 (4700 4385);
PAINT MONO (4700 4385);
DISPLAY INVISIBLE (4700 4385);
WIRE 16 -1 (6700 1975)(7100 1975);
FORCEPROP 2 LAST SIG_NAME IND_CPU1_P0_CPL6
J 0
(6740 1985);
DISPLAY 0.489362 (6740 1985);
WIRE 16 -1 (4800 1925)(4800 1575);
FORCEPROP 2 LAST SIG_NAME SW_PVDDCR_CPU1_P0_SW6_RC
J 0
(4840 1650);
DISPLAY 0.489362 (4840 1650);
FORCEPROP 2 LASTPROP $XRERR UNIQUE?
J 0
(4600 1650);
DISPLAY 0.638298 (4600 1650);
PAINT MONO (4600 1650);
DISPLAY INVISIBLE (4600 1650);
WIRE 16 -1 (3775 1925)(4375 1925);
FORCEPROP 2 LAST SIG_NAME NC_PVDDCR_CPU1_P0_GL1_6
J 0
(3890 1935);
DISPLAY 0.489362 (3890 1935);
FORCEPROP 2 LASTPROP $XRERR UNIQUE?
J 0
(4405 1925);
DISPLAY 0.638298 (4405 1925);
PAINT MONO (4405 1925);
DISPLAY INVISIBLE (4405 1925);
WIRE 16 -1 (3800 4525)(4400 4525);
FORCEPROP 2 LAST SIG_NAME NC_PVDDCR_CPU1_P0_GL2_5
J 0
(3915 4535);
DISPLAY 0.489362 (3915 4535);
FORCEPROP 2 LASTPROP $XRERR UNIQUE?
J 0
(4430 4525);
DISPLAY 0.638298 (4430 4525);
PAINT MONO (4430 4525);
DISPLAY INVISIBLE (4430 4525);
WIRE 16 -1 (3800 4575)(4400 4575);
FORCEPROP 2 LAST SIG_NAME NC_PVDDCR_CPU1_P0_GL1_5
J 0
(3915 4585);
DISPLAY 0.489362 (3915 4585);
FORCEPROP 2 LASTPROP $XRERR UNIQUE?
J 0
(4430 4575);
DISPLAY 0.638298 (4430 4575);
PAINT MONO (4430 4575);
DISPLAY INVISIBLE (4430 4575);
WIRE 16 -1 (1925 5400)(1925 5500);
WIRE 16 -1 (1925 5500)(2250 5500);
WIRE 16 -1 (1925 5750)(1925 5500);
WIRE 16 -1 (2250 5500)(2250 5225);
WIRE 16 -1 (2850 5225)(2250 5225);
FORCEPROP 2 LAST SIG_NAME PVDDCR_CPU1_P0_VCC5
J 0
(2315 5235);
DISPLAY 0.489362 (2315 5235);
FORCEPROP 2 LASTPROP $XRERR UNIQUE?
J 0
(2075 5235);
DISPLAY 0.638298 (2075 5235);
PAINT MONO (2075 5235);
DISPLAY INVISIBLE (2075 5235);
WIRE 16 -1 (2850 5225)(2950 5225);
WIRE 16 -1 (2850 5025)(2850 5225);
WIRE 16 -1 (2950 5025)(2850 5025);
WIRE 16 -1 (2950 4625)(2575 4625);
FORCEPROP 2 LAST SIG_NAME NC_PVDDCR_CPU1_P0_DNC5
J 0
(2380 4635);
DISPLAY 0.489362 (2380 4635);
FORCEPROP 2 LASTPROP $XRERR UNIQUE?
J 0
(2335 4625);
DISPLAY 0.638298 (2335 4625);
PAINT MONO (2335 4625);
DISPLAY INVISIBLE (2335 4625);
WIRE 16 -1 (2950 4875)(2000 4875);
FORCEPROP 2 LAST SIG_NAME PVDDCR_CPU1_P0_IMON5
J 0
(2115 4885);
DISPLAY 0.489362 (2115 4885);
WIRE 16 -1 (1475 4575)(2950 4575);
FORCEPROP 2 LAST SIG_NAME PVDDCR_CPU1_P0_LSET5
J 0
(1990 4585);
DISPLAY 0.489362 (1990 4585);
FORCEPROP 2 LASTPROP $XRERR UNIQUE?
J 0
(1750 4585);
DISPLAY 0.638298 (1750 4585);
PAINT MONO (1750 4585);
DISPLAY INVISIBLE (1750 4585);
WIRE 16 -1 (1475 4575)(1475 4475);
WIRE 16 -1 (1900 2750)(1900 2850);
WIRE 16 -1 (1900 2850)(2225 2850);
WIRE 16 -1 (1900 3100)(1900 2850);
WIRE 16 -1 (2225 2850)(2225 2575);
WIRE 16 -1 (2825 2575)(2225 2575);
FORCEPROP 2 LAST SIG_NAME PVDDCR_CPU1_P0_VCC6
J 0
(2290 2585);
DISPLAY 0.489362 (2290 2585);
FORCEPROP 2 LASTPROP $XRERR UNIQUE?
J 0
(2050 2585);
DISPLAY 0.638298 (2050 2585);
PAINT MONO (2050 2585);
DISPLAY INVISIBLE (2050 2585);
WIRE 16 -1 (2825 2575)(2925 2575);
WIRE 16 -1 (2825 2375)(2825 2575);
WIRE 16 -1 (2925 2375)(2825 2375);
WIRE 16 -1 (2925 1975)(2550 1975);
FORCEPROP 2 LAST SIG_NAME NC_PVDDCR_CPU1_P0_DNC6
J 0
(2355 1985);
DISPLAY 0.489362 (2355 1985);
FORCEPROP 2 LASTPROP $XRERR UNIQUE?
J 0
(2310 1975);
DISPLAY 0.638298 (2310 1975);
PAINT MONO (2310 1975);
DISPLAY INVISIBLE (2310 1975);
WIRE 16 -1 (2925 1725)(1975 1725);
FORCEPROP 2 LAST SIG_NAME PVDDCR_CPU1_P0_TEMP0
J 0
(2090 1735);
DISPLAY 0.489362 (2090 1735);
WIRE 16 -1 (2825 2125)(2825 2050);
FORCEPROP 0 LAST CDS_PHYS_NET_NAME PVDDCR_CPU1_P0_VCCS
J 0
(2825 2075);
PAINT MONO (2825 2075);
DISPLAY INVISIBLE (2825 2075);
WIRE 16 -1 (2825 2125)(2925 2125);
WIRE 16 -1 (1975 2125)(2825 2125);
FORCEPROP 2 LAST SIG_NAME PVDDCR_CPU1_P0_VCCS
J 0
(2090 2135);
DISPLAY 0.489362 (2090 2135);
WIRE 16 -1 (2825 2050)(950 2050);
WIRE 16 -1 (950 2050)(950 1950);
WIRE 16 -1 (2925 2225)(1975 2225);
FORCEPROP 2 LAST SIG_NAME PVDDCR_CPU1_P0_IMON6
J 0
(2090 2235);
DISPLAY 0.489362 (2090 2235);
WIRE 16 -1 (2950 4375)(2000 4375);
FORCEPROP 2 LAST SIG_NAME PVDDCR_CPU1_P0_TEMP0
J 0
(2115 4385);
DISPLAY 0.489362 (2115 4385);
WIRE 16 -1 (2925 1625)(1975 1625);
FORCEPROP 2 LAST SIG_NAME PVDDCR_CPU1_P0_PWM6
J 0
(2090 1635);
DISPLAY 0.489362 (2090 1635);
WIRE 16 -1 (2950 4275)(2000 4275);
FORCEPROP 2 LAST SIG_NAME PVDDCR_CPU1_P0_PWM5
J 0
(2115 4285);
DISPLAY 0.489362 (2115 4285);
WIRE 16 -1 (1450 1925)(2925 1925);
FORCEPROP 2 LAST SIG_NAME PVDDCR_CPU1_P0_LSET6
J 0
(1965 1935);
DISPLAY 0.489362 (1965 1935);
FORCEPROP 2 LASTPROP $XRERR UNIQUE?
J 0
(1725 1935);
DISPLAY 0.638298 (1725 1935);
PAINT MONO (1725 1935);
DISPLAY INVISIBLE (1725 1935);
WIRE 16 -1 (1450 1925)(1450 1825);
DOT 1 (1900 2850);
DOT 1 (1900 3425);
DOT 1 (2825 2125);
DOT 1 (4025 1675);
DOT 1 (4025 1625);
DOT 1 (4025 1725);
DOT 1 (2825 2575);
DOT 1 (2250 3425);
DOT 1 (3950 2875);
DOT 1 (4050 4275);
DOT 1 (4050 4325);
DOT 1 (4050 4375);
DOT 1 (1925 5500);
DOT 1 (1925 6075);
DOT 1 (2850 4775);
DOT 1 (2850 5225);
DOT 1 (2275 6075);
DOT 1 (4800 2225);
DOT 1 (4650 2875);
DOT 1 (4225 3375);
DOT 1 (4650 3375);
DOT 1 (5050 2875);
DOT 1 (5050 3375);
DOT 1 (5450 2875);
DOT 1 (5450 3375);
DOT 1 (5825 2875);
DOT 1 (5825 3375);
DOT 1 (7375 2225);
DOT 1 (7675 2225);
DOT 1 (8100 1800);
DOT 1 (8100 2225);
DOT 1 (4900 4875);
DOT 1 (4250 6025);
DOT 1 (5075 5525);
DOT 1 (4675 6025);
DOT 1 (5075 6025);
DOT 1 (5475 5525);
DOT 1 (5475 6025);
DOT 1 (5850 5525);
DOT 1 (5850 6025);
DOT 1 (7400 4875);
DOT 1 (7700 4875);
DOT 1 (8125 4450);
DOT 1 (8125 4875);
DOT 1 (3975 5525);
DOT 1 (4675 5525);
FORCENOTE
2ND=CV+12^0EZ04
(5225 1725) 0;
DISPLAY LEFT (5225 1725);
DISPLAY 0.638298 (5225 1725);
PAINT WHITE (5225 1725);
FORCENOTE
DCR=0.17M OHM
(5225 1775) 0;
DISPLAY LEFT (5225 1775);
DISPLAY 0.638298 (5225 1775);
PAINT WHITE (5225 1775);
FORCENOTE
6.5*6.5*10.0
(5225 1825) 0;
DISPLAY LEFT (5225 1825);
DISPLAY 0.638298 (5225 1825);
PAINT WHITE (5225 1825);
FORCENOTE
ISAT:60A@100C
(5225 1875) 0;
DISPLAY LEFT (5225 1875);
DISPLAY 0.638298 (5225 1875);
PAINT WHITE (5225 1875);
FORCENOTE
PGL6312.121AHLT
(5225 1925) 0;
DISPLAY LEFT (5225 1925);
DISPLAY 0.638298 (5225 1925);
PAINT WHITE (5225 1925);
FORCENOTE
PVDDCR_CPU1_P0_PHASE5
(3025 6050) 0;
DISPLAY LEFT (3025 6050);
DISPLAY 1.021277 (3025 6050);
PAINT WHITE (3025 6050);
FORCENOTE
2ND=CV+15^0TZ01
(6750 2300) 0;
DISPLAY LEFT (6750 2300);
DISPLAY 0.638298 (6750 2300);
PAINT WHITE (6750 2300);
FORCENOTE
DCR=2-3,0.27M OHM
(6750 2350) 0;
DISPLAY LEFT (6750 2350);
DISPLAY 0.638298 (6750 2350);
PAINT WHITE (6750 2350);
FORCENOTE
11.0*7.5*12.5
(6750 2450) 0;
DISPLAY LEFT (6750 2450);
DISPLAY 0.638298 (6750 2450);
PAINT WHITE (6750 2450);
FORCENOTE
ISAT:70A@100C
(6750 2500) 0;
DISPLAY LEFT (6750 2500);
DISPLAY 0.638298 (6750 2500);
PAINT WHITE (6750 2500);
FORCENOTE
PGL6303.151HLT
(6750 2550) 0;
DISPLAY LEFT (6750 2550);
DISPLAY 0.638298 (6750 2550);
PAINT WHITE (6750 2550);
FORCENOTE
DCR=1-4,0.105M OHM
(6750 2400) 0;
DISPLAY LEFT (6750 2400);
DISPLAY 0.638298 (6750 2400);
PAINT WHITE (6750 2400);
FORCENOTE
PGL6303.151HLT
(6750 5200) 0;
DISPLAY LEFT (6750 5200);
DISPLAY 0.638298 (6750 5200);
PAINT WHITE (6750 5200);
FORCENOTE
ISAT:70A@100C
(6750 5150) 0;
DISPLAY LEFT (6750 5150);
DISPLAY 0.638298 (6750 5150);
PAINT WHITE (6750 5150);
FORCENOTE
11.0*7.5*12.5
(6750 5100) 0;
DISPLAY LEFT (6750 5100);
DISPLAY 0.638298 (6750 5100);
PAINT WHITE (6750 5100);
FORCENOTE
2ND=CV+15^0TZ01
(6750 4950) 0;
DISPLAY LEFT (6750 4950);
DISPLAY 0.638298 (6750 4950);
PAINT WHITE (6750 4950);
FORCENOTE
DCR=2-3,0.27M OHM
(6750 5000) 0;
DISPLAY LEFT (6750 5000);
DISPLAY 0.638298 (6750 5000);
PAINT WHITE (6750 5000);
FORCENOTE
DCR=1-4,0.105M OHM
(6750 5050) 0;
DISPLAY LEFT (6750 5050);
DISPLAY 0.638298 (6750 5050);
PAINT WHITE (6750 5050);
FORCENOTE
PVDDCR_CPU1_P0_PHASE6
(3000 3400) 0;
DISPLAY LEFT (3000 3400);
DISPLAY 1.021277 (3000 3400);
PAINT WHITE (3000 3400);
QUIT
